FILE_TYPE = MACRO_DRAWING;
SET COLOR_WIRE YELLOW;
SET COLOR_PROP ORANGE;
SET COLOR_DOT WHITE;
SET COLOR_ARC YELLOW;
SET COLOR_BODY GREEN;
SET COLOR_NOTE PURPLE;
SET PROP_DISPLAY VALUE;
SET PAGE_NUMBER P223;
FORCEADD UNIVERSAL_GND..1
(-1350 3500);
FORCEPROP 3 LASTPIN (-1350 3550) SIG_NAME GND\g
J 0
(-1340 3560);
DISPLAY 0.659574 (-1340 3560);
PAINT MONO (-1340 3560);
DISPLAY INVISIBLE (-1340 3560);
FORCEPROP 2 LAST CDS_LIB logical_power
J 0
(-1350 3500);
DISPLAY INVISIBLE (-1350 3500);
FORCEPROP 1 LAST HDL_POWER GND
J 1
(-1325 3425);
DISPLAY 0.872340 (-1325 3425);
PAINT GREEN (-1325 3425);
DISPLAY INVISIBLE (-1325 3425);
FORCEPROP 1 LAST PATH I10
J 0
(-1275 3500);
DISPLAY 0.872340 (-1275 3500);
PAINT AQUA (-1275 3500);
DISPLAY INVISIBLE (-1275 3500);
FORCEADD Q_RES..1
(-5600 5425);
FORCEPROP 1 LAST PART_NUMBER CS03322FB03
J 0
(-5725 5475);
DISPLAY 0.404255 (-5725 5475);
DISPLAY INVISIBLE (-5725 5475);
FORCEPROP 1 LAST VALUE 33.2
J 2
(-5400 5425);
DISPLAY 0.510638 (-5400 5425);
FORCEPROP 1 LAST TOLERANCE 1%
J 0
(-5375 5425);
DISPLAY 0.510638 (-5375 5425);
FORCEPROP 1 LAST MATERIAL CHIP
J 0
(-5300 5425);
DISPLAY 0.510638 (-5300 5425);
FORCEPROP 1 LAST LOCATION R962
J 0
(-5800 5425);
DISPLAY 0.638298 (-5800 5425);
FORCEPROP 1 LASTPIN (-5700 5425) $PN 1
J 0
(-5688 5437);
DISPLAY 0.787234 (-5688 5437);
PAINT MONO (-5688 5437);
FORCEPROP 1 LASTPIN (-5500 5425) $PN 2
J 0
(-5538 5437);
DISPLAY 0.787234 (-5538 5437);
PAINT MONO (-5538 5437);
FORCEPROP 2 LAST CDS_LIB pure_quanta
J 0
(-5600 5425);
DISPLAY INVISIBLE (-5600 5425);
FORCEPROP 1 LAST WATTAGE 1/16W
J 2
(-5500 5525);
DISPLAY 0.404255 (-5500 5525);
DISPLAY INVISIBLE (-5500 5525);
FORCEPROP 1 LAST PACK_TYPE 0402LF
J 0
(-5725 5525);
DISPLAY 0.404255 (-5725 5525);
DISPLAY INVISIBLE (-5725 5525);
FORCEPROP 1 LAST PATH I100
J 0
(-5650 5575);
DISPLAY 0.978723 (-5650 5575);
PAINT WHITE (-5650 5575);
DISPLAY INVISIBLE (-5650 5575);
FORCEPROP 0 LAST $SEC 1
J 0
(-5800 5475);
DISPLAY 0.680851 (-5800 5475);
PAINT MONO (-5800 5475);
DISPLAY INVISIBLE (-5800 5475);
FORCEPROP 0 LAST CDS_SEC 1
J 0
(-5800 5475);
DISPLAY 1.021277 (-5800 5475);
DISPLAY INVISIBLE (-5800 5475);
FORCEADD Q_RES..1
(-5600 7125);
FORCEPROP 1 LAST PART_NUMBER CS03322FB03
J 0
(-5725 7175);
DISPLAY 0.404255 (-5725 7175);
DISPLAY INVISIBLE (-5725 7175);
FORCEPROP 1 LAST VALUE 33.2
J 2
(-5400 7125);
DISPLAY 0.510638 (-5400 7125);
FORCEPROP 1 LAST TOLERANCE 1%
J 0
(-5375 7125);
DISPLAY 0.510638 (-5375 7125);
FORCEPROP 1 LAST MATERIAL CHIP
J 0
(-5300 7125);
DISPLAY 0.510638 (-5300 7125);
FORCEPROP 1 LAST LOCATION R960
J 0
(-5800 7125);
DISPLAY 0.638298 (-5800 7125);
FORCEPROP 1 LASTPIN (-5700 7125) $PN 1
J 0
(-5688 7137);
DISPLAY 0.787234 (-5688 7137);
PAINT MONO (-5688 7137);
FORCEPROP 1 LASTPIN (-5500 7125) $PN 2
J 0
(-5538 7137);
DISPLAY 0.787234 (-5538 7137);
PAINT MONO (-5538 7137);
FORCEPROP 1 LAST WATTAGE 1/16W
J 2
(-5500 7225);
DISPLAY 0.404255 (-5500 7225);
DISPLAY INVISIBLE (-5500 7225);
FORCEPROP 1 LAST PACK_TYPE 0402LF
J 0
(-5725 7225);
DISPLAY 0.404255 (-5725 7225);
DISPLAY INVISIBLE (-5725 7225);
FORCEPROP 2 LAST CDS_LIB pure_quanta
J 0
(-5600 7125);
DISPLAY INVISIBLE (-5600 7125);
FORCEPROP 1 LAST PATH I101
J 0
(-5650 7275);
DISPLAY 0.978723 (-5650 7275);
PAINT WHITE (-5650 7275);
DISPLAY INVISIBLE (-5650 7275);
FORCEPROP 0 LAST $SEC 1
J 0
(-5800 7175);
DISPLAY 0.680851 (-5800 7175);
PAINT MONO (-5800 7175);
DISPLAY INVISIBLE (-5800 7175);
FORCEPROP 0 LAST CDS_SEC 1
J 0
(-5800 7175);
DISPLAY 1.021277 (-5800 7175);
DISPLAY INVISIBLE (-5800 7175);
FORCEADD Q_RES..1
(-5600 7025);
FORCEPROP 1 LAST PART_NUMBER CS03322FB03
J 0
(-5725 7075);
DISPLAY 0.404255 (-5725 7075);
DISPLAY INVISIBLE (-5725 7075);
FORCEPROP 1 LAST MATERIAL CHIP
J 0
(-5300 7025);
DISPLAY 0.510638 (-5300 7025);
FORCEPROP 1 LAST TOLERANCE 1%
J 0
(-5375 7025);
DISPLAY 0.510638 (-5375 7025);
FORCEPROP 1 LAST VALUE 33.2
J 2
(-5400 7025);
DISPLAY 0.510638 (-5400 7025);
FORCEPROP 1 LAST LOCATION R909
J 0
(-5800 7025);
DISPLAY 0.638298 (-5800 7025);
FORCEPROP 1 LASTPIN (-5700 7025) $PN 1
J 0
(-5688 7037);
DISPLAY 0.787234 (-5688 7037);
PAINT MONO (-5688 7037);
FORCEPROP 1 LASTPIN (-5500 7025) $PN 2
J 0
(-5538 7037);
DISPLAY 0.787234 (-5538 7037);
PAINT MONO (-5538 7037);
FORCEPROP 1 LAST PACK_TYPE 0402LF
J 0
(-5725 7125);
DISPLAY 0.404255 (-5725 7125);
DISPLAY INVISIBLE (-5725 7125);
FORCEPROP 1 LAST WATTAGE 1/16W
J 2
(-5500 7125);
DISPLAY 0.404255 (-5500 7125);
DISPLAY INVISIBLE (-5500 7125);
FORCEPROP 2 LAST CDS_LIB pure_quanta
J 0
(-5600 7025);
DISPLAY INVISIBLE (-5600 7025);
FORCEPROP 1 LAST PATH I102
J 0
(-5650 7175);
DISPLAY 0.978723 (-5650 7175);
PAINT WHITE (-5650 7175);
DISPLAY INVISIBLE (-5650 7175);
FORCEPROP 0 LAST $SEC 1
J 0
(-5800 7075);
DISPLAY 0.680851 (-5800 7075);
PAINT MONO (-5800 7075);
DISPLAY INVISIBLE (-5800 7075);
FORCEPROP 0 LAST CDS_SEC 1
J 0
(-5800 7075);
DISPLAY 1.021277 (-5800 7075);
DISPLAY INVISIBLE (-5800 7075);
FORCEADD MOSFET_NCH_DUAL..1
(-2550 3800);
FORCEPROP 1 LAST PART_NUMBER BAM138K0003
J 0
(-2399 3714);
DISPLAY 0.723404 (-2399 3714);
PAINT GREEN (-2399 3714);
DISPLAY INVISIBLE (-2399 3714);
FORCEPROP 2 LAST PART_TYPE SMLF
J 0
(-2375 3875);
DISPLAY 1.021277 (-2375 3875);
FORCEPROP 1 LAST MATERIAL IC
J 0
(-2399 3649);
DISPLAY 0.723404 (-2399 3649);
PAINT GREEN (-2399 3649);
FORCEPROP 2 LAST VALUE PJT138K
J 0
(-2375 3825);
DISPLAY 1.021277 (-2375 3825);
FORCEPROP 1 LAST LOCATION Q15
J 0
(-2399 3774);
DISPLAY 0.723404 (-2399 3774);
PAINT GREEN (-2399 3774);
FORCEPROP 2 LASTPIN (-2500 4000) $PN 6
R 1
J 0
(-2510 4010);
DISPLAY 0.680851 (-2510 4010);
PAINT MONO (-2510 4010);
FORCEPROP 2 LASTPIN (-2750 3750) $PN 2
J 2
(-2760 3760);
DISPLAY 0.680851 (-2760 3760);
PAINT MONO (-2760 3760);
FORCEPROP 2 LASTPIN (-2500 3600) $PN 1
R 1
J 2
(-2510 3590);
DISPLAY 0.680851 (-2510 3590);
PAINT MONO (-2510 3590);
FORCEPROP 2 LAST CDS_LIB pure_quanta
J 0
(-2550 3800);
DISPLAY INVISIBLE (-2550 3800);
FORCEPROP 1 LAST CDS_LMAN_SYM_OUTLINE -150,150,150,-150
J 0
(-2550 3800);
DISPLAY 0.468085 (-2550 3800);
PAINT GREEN (-2550 3800);
DISPLAY INVISIBLE (-2550 3800);
FORCEPROP 2 LAST SEC_TYPE 
J 0
(-2375 3925);
DISPLAY 1.021277 (-2375 3925);
DISPLAY INVISIBLE (-2375 3925);
FORCEPROP 1 LAST NEEDS_NO_SIZE TRUE
J 0
(-2550 3799);
DISPLAY 0.468085 (-2550 3799);
PAINT GREEN (-2550 3799);
DISPLAY INVISIBLE (-2550 3799);
FORCEPROP 1 LAST PATH I104
J 0
(-2550 3800);
DISPLAY 0.723404 (-2550 3800);
PAINT GREEN (-2550 3800);
DISPLAY INVISIBLE (-2550 3800);
FORCEPROP 2 LAST SEC 1
J 0
(-2375 3925);
DISPLAY 0.680851 (-2375 3925);
PAINT MONO (-2375 3925);
DISPLAY INVISIBLE (-2375 3925);
FORCEADD MOSFET_NCH_DUAL..1
(-2550 2500);
FORCEPROP 1 LAST PART_NUMBER BAM138K0003
J 0
(-2399 2414);
DISPLAY 0.723404 (-2399 2414);
PAINT GREEN (-2399 2414);
DISPLAY INVISIBLE (-2399 2414);
FORCEPROP 2 LAST PART_TYPE SMLF
J 0
(-2375 2575);
DISPLAY 1.021277 (-2375 2575);
FORCEPROP 1 LAST MATERIAL IC
J 0
(-2399 2349);
DISPLAY 0.723404 (-2399 2349);
PAINT GREEN (-2399 2349);
FORCEPROP 2 LAST VALUE PJT138K
J 0
(-2375 2525);
DISPLAY 1.021277 (-2375 2525);
FORCEPROP 1 LAST LOCATION Q16
J 0
(-2399 2474);
DISPLAY 0.723404 (-2399 2474);
PAINT GREEN (-2399 2474);
FORCEPROP 0 LASTPIN (-2500 2700) $PN 6
R 1
J 0
(-2510 2710);
DISPLAY 0.680851 (-2510 2710);
PAINT MONO (-2510 2710);
FORCEPROP 0 LASTPIN (-2750 2450) $PN 2
J 2
(-2760 2460);
DISPLAY 0.680851 (-2760 2460);
PAINT MONO (-2760 2460);
FORCEPROP 0 LASTPIN (-2500 2300) $PN 1
R 1
J 2
(-2510 2290);
DISPLAY 0.680851 (-2510 2290);
PAINT MONO (-2510 2290);
FORCEPROP 2 LAST CDS_LIB pure_quanta
J 0
(-2550 2500);
DISPLAY INVISIBLE (-2550 2500);
FORCEPROP 1 LAST CDS_LMAN_SYM_OUTLINE -150,150,150,-150
J 0
(-2550 2500);
DISPLAY 0.468085 (-2550 2500);
PAINT GREEN (-2550 2500);
DISPLAY INVISIBLE (-2550 2500);
FORCEPROP 1 LAST NEEDS_NO_SIZE TRUE
J 0
(-2550 2499);
DISPLAY 0.468085 (-2550 2499);
PAINT GREEN (-2550 2499);
DISPLAY INVISIBLE (-2550 2499);
FORCEPROP 1 LAST PATH I106
J 0
(-2550 2500);
DISPLAY 0.723404 (-2550 2500);
PAINT GREEN (-2550 2500);
DISPLAY INVISIBLE (-2550 2500);
FORCEPROP 0 LAST $SEC 1
J 0
(-2375 2625);
DISPLAY 0.680851 (-2375 2625);
PAINT MONO (-2375 2625);
DISPLAY INVISIBLE (-2375 2625);
FORCEPROP 0 LAST CDS_SEC 1
J 0
(-2375 2625);
DISPLAY 1.021277 (-2375 2625);
DISPLAY INVISIBLE (-2375 2625);
FORCEADD MOSFET_NCH_DUAL..2
(-1400 3800);
FORCEPROP 1 LAST PART_NUMBER BAM138K0003
J 0
(-1249 3706);
DISPLAY 0.723404 (-1249 3706);
PAINT GREEN (-1249 3706);
DISPLAY INVISIBLE (-1249 3706);
FORCEPROP 1 LAST MATERIAL IC
J 0
(-1249 3651);
DISPLAY 0.723404 (-1249 3651);
PAINT GREEN (-1249 3651);
FORCEPROP 2 LAST PART_TYPE SMLF
J 0
(-1225 3875);
DISPLAY 1.021277 (-1225 3875);
FORCEPROP 2 LAST VALUE PJT138K
J 0
(-1225 3825);
DISPLAY 1.021277 (-1225 3825);
FORCEPROP 1 LAST LOCATION Q15
J 0
(-1249 3776);
DISPLAY 0.723404 (-1249 3776);
PAINT GREEN (-1249 3776);
FORCEPROP 0 LASTPIN (-1350 4000) $PN 3
R 1
J 0
(-1360 4010);
DISPLAY 0.680851 (-1360 4010);
PAINT MONO (-1360 4010);
FORCEPROP 0 LASTPIN (-1600 3750) $PN 5
J 2
(-1610 3760);
DISPLAY 0.680851 (-1610 3760);
PAINT MONO (-1610 3760);
FORCEPROP 0 LASTPIN (-1350 3600) $PN 4
R 1
J 2
(-1360 3590);
DISPLAY 0.680851 (-1360 3590);
PAINT MONO (-1360 3590);
FORCEPROP 2 LAST CDS_LIB pure_quanta
J 0
(-1400 3800);
DISPLAY INVISIBLE (-1400 3800);
FORCEPROP 1 LAST CDS_LMAN_SYM_OUTLINE -150,150,150,-150
J 0
(-1400 3800);
DISPLAY 0.468085 (-1400 3800);
PAINT GREEN (-1400 3800);
DISPLAY INVISIBLE (-1400 3800);
FORCEPROP 1 LAST NEEDS_NO_SIZE TRUE
J 0
(-1250 3691);
DISPLAY 0.468085 (-1250 3691);
PAINT GREEN (-1250 3691);
DISPLAY INVISIBLE (-1250 3691);
FORCEPROP 1 LAST PATH I108
J 0
(-1250 3650);
DISPLAY 0.723404 (-1250 3650);
PAINT GREEN (-1250 3650);
DISPLAY INVISIBLE (-1250 3650);
FORCEPROP 0 LAST $SEC 2
J 0
(-1225 3925);
DISPLAY 0.680851 (-1225 3925);
PAINT MONO (-1225 3925);
DISPLAY INVISIBLE (-1225 3925);
FORCEPROP 0 LAST CDS_SEC 2
J 0
(-1225 3925);
DISPLAY 1.021277 (-1225 3925);
DISPLAY INVISIBLE (-1225 3925);
FORCEADD MOSFET_NCH_DUAL..2
(-1400 2500);
FORCEPROP 1 LAST PART_NUMBER BAM138K0003
J 0
(-1249 2406);
DISPLAY 0.723404 (-1249 2406);
PAINT GREEN (-1249 2406);
DISPLAY INVISIBLE (-1249 2406);
FORCEPROP 1 LAST MATERIAL IC
J 0
(-1249 2351);
DISPLAY 0.723404 (-1249 2351);
PAINT GREEN (-1249 2351);
FORCEPROP 2 LAST VALUE PJT138K
J 0
(-1225 2525);
DISPLAY 1.021277 (-1225 2525);
FORCEPROP 2 LAST PART_TYPE SMLF
J 0
(-1225 2575);
DISPLAY 1.021277 (-1225 2575);
FORCEPROP 1 LAST LOCATION Q16
J 0
(-1249 2476);
DISPLAY 0.723404 (-1249 2476);
PAINT GREEN (-1249 2476);
FORCEPROP 0 LASTPIN (-1350 2700) $PN 3
R 1
J 0
(-1360 2710);
DISPLAY 0.680851 (-1360 2710);
PAINT MONO (-1360 2710);
FORCEPROP 0 LASTPIN (-1600 2450) $PN 5
J 2
(-1610 2460);
DISPLAY 0.680851 (-1610 2460);
PAINT MONO (-1610 2460);
FORCEPROP 0 LASTPIN (-1350 2300) $PN 4
R 1
J 2
(-1360 2290);
DISPLAY 0.680851 (-1360 2290);
PAINT MONO (-1360 2290);
FORCEPROP 1 LAST CDS_LMAN_SYM_OUTLINE -150,150,150,-150
J 0
(-1400 2500);
DISPLAY 0.468085 (-1400 2500);
PAINT GREEN (-1400 2500);
DISPLAY INVISIBLE (-1400 2500);
FORCEPROP 2 LAST CDS_LIB pure_quanta
J 0
(-1400 2500);
DISPLAY INVISIBLE (-1400 2500);
FORCEPROP 1 LAST NEEDS_NO_SIZE TRUE
J 0
(-1250 2391);
DISPLAY 0.468085 (-1250 2391);
PAINT GREEN (-1250 2391);
DISPLAY INVISIBLE (-1250 2391);
FORCEPROP 1 LAST PATH I109
J 0
(-1250 2350);
DISPLAY 0.723404 (-1250 2350);
PAINT GREEN (-1250 2350);
DISPLAY INVISIBLE (-1250 2350);
FORCEPROP 0 LAST $SEC 2
J 0
(-1225 2625);
DISPLAY 0.680851 (-1225 2625);
PAINT MONO (-1225 2625);
DISPLAY INVISIBLE (-1225 2625);
FORCEPROP 0 LAST CDS_SEC 2
J 0
(-1225 2625);
DISPLAY 1.021277 (-1225 2625);
DISPLAY INVISIBLE (-1225 2625);
FORCEADD UNIVERSAL_POWER..1
(-1350 3275);
FORCEPROP 3 LASTPIN (-1350 3225) SIG_NAME PVNN_TERM_CPU1\g
J 0
(-1340 3235);
DISPLAY 0.659574 (-1340 3235);
PAINT MONO (-1340 3235);
DISPLAY INVISIBLE (-1340 3235);
FORCEPROP 1 LAST HDL_POWER PVNN_TERM_CPU1
J 1
(-1350 3325);
DISPLAY 0.872340 (-1350 3325);
PAINT GREEN (-1350 3325);
FORCEPROP 2 LAST CDS_LIB logical_power
J 0
(-1350 3275);
DISPLAY INVISIBLE (-1350 3275);
FORCEPROP 1 LAST PATH I11
J 0
(-1300 3300);
DISPLAY 0.872340 (-1300 3300);
PAINT AQUA (-1300 3300);
DISPLAY INVISIBLE (-1300 3300);
FORCEADD Q_RES..2
(-1350 3025);
FORCEPROP 1 LAST PART_NUMBER CS24702JB10
J 0
(-1310 2900);
DISPLAY 0.510638 (-1310 2900);
DISPLAY INVISIBLE (-1310 2900);
FORCEPROP 1 LAST WATTAGE 1/16W
J 0
(-1310 3000);
DISPLAY 0.510638 (-1310 3000);
FORCEPROP 1 LAST VALUE 4.7K
J 0
(-1305 3100);
DISPLAY 0.510638 (-1305 3100);
FORCEPROP 1 LAST TOLERANCE 5%
J 0
(-1305 3050);
DISPLAY 0.510638 (-1305 3050);
FORCEPROP 1 LAST PACK_TYPE 0402LF
J 0
(-1310 2850);
DISPLAY 0.510638 (-1310 2850);
FORCEPROP 1 LAST MATERIAL CHIP
J 0
(-1310 2950);
DISPLAY 0.510638 (-1310 2950);
FORCEPROP 1 LAST $LOCATION R1007
J 0
(-1305 3150);
DISPLAY 0.787234 (-1305 3150);
FORCEPROP 1 LASTPIN (-1350 3125) $PN 1
J 0
(-1345 3087);
DISPLAY 0.787234 (-1345 3087);
FORCEPROP 1 LASTPIN (-1350 2925) $PN 2
J 0
(-1345 2935);
DISPLAY 0.787234 (-1345 2935);
FORCEPROP 2 LAST CDS_LIB pure_quanta
J 0
(-1350 3025);
PAINT MONO (-1350 3025);
DISPLAY INVISIBLE (-1350 3025);
FORCEPROP 1 LAST PATH I12
J 0
(-1300 3200);
DISPLAY 0.978723 (-1300 3200);
PAINT WHITE (-1300 3200);
DISPLAY INVISIBLE (-1300 3200);
FORCEPROP 2 LAST CDS_LOCATION R1007
J 0
(-1300 3250);
DISPLAY 1.021277 (-1300 3250);
DISPLAY INVISIBLE (-1300 3250);
FORCEPROP 2 LAST $SEC 1
J 0
(-1300 3250);
DISPLAY 0.680851 (-1300 3250);
PAINT MONO (-1300 3250);
DISPLAY INVISIBLE (-1300 3250);
FORCEPROP 2 LAST CDS_SEC 1
J 0
(-1300 3250);
DISPLAY 1.021277 (-1300 3250);
DISPLAY INVISIBLE (-1300 3250);
FORCEADD UNIVERSAL_POWER..1
(-3000 7925);
FORCEPROP 3 LASTPIN (-3000 7875) SIG_NAME P3V3_AUX\g
J 0
(-2990 7885);
DISPLAY 0.659574 (-2990 7885);
PAINT MONO (-2990 7885);
DISPLAY INVISIBLE (-2990 7885);
FORCEPROP 1 LAST HDL_POWER P3V3_AUX
J 1
(-3000 7975);
DISPLAY 0.872340 (-3000 7975);
PAINT GREEN (-3000 7975);
FORCEPROP 2 LAST CDS_LIB logical_power
J 0
(-3000 7925);
PAINT MONO (-3000 7925);
DISPLAY INVISIBLE (-3000 7925);
FORCEPROP 1 LAST PATH I16
J 0
(-2950 7950);
DISPLAY 0.872340 (-2950 7950);
PAINT AQUA (-2950 7950);
DISPLAY INVISIBLE (-2950 7950);
FORCEADD UNIVERSAL_GND..1
(-3000 7375);
FORCEPROP 3 LASTPIN (-3000 7425) SIG_NAME GND\g
J 0
(-2990 7435);
DISPLAY 0.659574 (-2990 7435);
PAINT MONO (-2990 7435);
DISPLAY INVISIBLE (-2990 7435);
FORCEPROP 2 LAST CDS_LIB logical_power
J 0
(-3000 7375);
PAINT MONO (-3000 7375);
DISPLAY INVISIBLE (-3000 7375);
FORCEPROP 1 LAST HDL_POWER GND
J 1
(-2975 7300);
DISPLAY 0.872340 (-2975 7300);
PAINT GREEN (-2975 7300);
DISPLAY INVISIBLE (-2975 7300);
FORCEPROP 1 LAST PATH I17
J 0
(-2925 7375);
DISPLAY 0.872340 (-2925 7375);
PAINT AQUA (-2925 7375);
DISPLAY INVISIBLE (-2925 7375);
FORCEADD Q_CAP..1
(-3000 7600);
FORCEPROP 1 LAST PART_NUMBER CH4104K1B00
J 0
(-2950 7450);
DISPLAY 0.510638 (-2950 7450);
DISPLAY INVISIBLE (-2950 7450);
FORCEPROP 1 LAST VALUE 0.1UF
J 0
(-2950 7650);
DISPLAY 0.510638 (-2950 7650);
FORCEPROP 1 LAST VOLTAGE 25V
J 0
(-2950 7600);
DISPLAY 0.510638 (-2950 7600);
FORCEPROP 1 LAST PACK_TYPE 0402
J 0
(-2950 7400);
DISPLAY 0.510638 (-2950 7400);
FORCEPROP 1 LAST MATERIAL X7R
J 0
(-2950 7500);
DISPLAY 0.510638 (-2950 7500);
FORCEPROP 1 LAST TOLERANCE 10%
J 0
(-2950 7550);
DISPLAY 0.510638 (-2950 7550);
FORCEPROP 1 LAST $LOCATION C561
J 0
(-2950 7700);
DISPLAY 0.978723 (-2950 7700);
FORCEPROP 1 LASTPIN (-3000 7700) $PN 1
J 0
(-2990 7680);
DISPLAY 0.787234 (-2990 7680);
FORCEPROP 1 LASTPIN (-3000 7500) $PN 2
J 0
(-2990 7480);
DISPLAY 0.787234 (-2990 7480);
FORCEPROP 2 LAST CDS_LIB pure_quanta
J 2
(-3000 7600);
PAINT MONO (-3000 7600);
DISPLAY INVISIBLE (-3000 7600);
FORCEPROP 1 LAST PATH I18
J 0
(-2950 7750);
DISPLAY 0.978723 (-2950 7750);
PAINT WHITE (-2950 7750);
DISPLAY INVISIBLE (-2950 7750);
FORCEPROP 2 LAST CDS_LOCATION C561
J 0
(-2950 7800);
DISPLAY 1.021277 (-2950 7800);
DISPLAY INVISIBLE (-2950 7800);
FORCEPROP 2 LAST $SEC 1
J 0
(-2950 7800);
DISPLAY 0.680851 (-2950 7800);
PAINT MONO (-2950 7800);
DISPLAY INVISIBLE (-2950 7800);
FORCEPROP 2 LAST CDS_SEC 1
J 0
(-2950 7800);
DISPLAY 1.021277 (-2950 7800);
DISPLAY INVISIBLE (-2950 7800);
FORCEADD UNIVERSAL_POWER..1
(-4350 7925);
FORCEPROP 3 LASTPIN (-4350 7875) SIG_NAME PVNN_TERM_CPU0\g
J 0
(-4340 7885);
DISPLAY 0.659574 (-4340 7885);
PAINT MONO (-4340 7885);
DISPLAY INVISIBLE (-4340 7885);
FORCEPROP 1 LAST HDL_POWER PVNN_TERM_CPU0
J 1
(-4350 7975);
DISPLAY 0.872340 (-4350 7975);
PAINT GREEN (-4350 7975);
FORCEPROP 2 LAST CDS_LIB logical_power
J 0
(-4350 7925);
PAINT MONO (-4350 7925);
DISPLAY INVISIBLE (-4350 7925);
FORCEPROP 1 LAST PATH I19
J 0
(-4300 7950);
DISPLAY 0.872340 (-4300 7950);
PAINT AQUA (-4300 7950);
DISPLAY INVISIBLE (-4300 7950);
FORCEADD Q_CAP..1
R 2
(-4350 7600);
FORCEPROP 1 LAST PART_NUMBER CH4104K1B00
J 2
(-4400 7450);
DISPLAY 0.510638 (-4400 7450);
DISPLAY INVISIBLE (-4400 7450);
FORCEPROP 1 LAST MATERIAL X7R
J 2
(-4400 7500);
DISPLAY 0.510638 (-4400 7500);
FORCEPROP 1 LAST TOLERANCE 10%
J 2
(-4400 7550);
DISPLAY 0.510638 (-4400 7550);
FORCEPROP 1 LAST VALUE 0.1UF
J 2
(-4400 7650);
DISPLAY 0.510638 (-4400 7650);
FORCEPROP 1 LAST VOLTAGE 25V
J 2
(-4400 7600);
DISPLAY 0.510638 (-4400 7600);
FORCEPROP 1 LAST PACK_TYPE 0402
J 2
(-4400 7400);
DISPLAY 0.510638 (-4400 7400);
FORCEPROP 1 LAST $LOCATION C559
J 2
(-4400 7700);
DISPLAY 0.978723 (-4400 7700);
FORCEPROP 1 LASTPIN (-4350 7700) $PN 1
J 2
(-4360 7680);
DISPLAY 0.787234 (-4360 7680);
FORCEPROP 1 LASTPIN (-4350 7500) $PN 2
J 2
(-4360 7480);
DISPLAY 0.787234 (-4360 7480);
FORCEPROP 2 LAST CDS_LIB pure_quanta
J 2
(-4350 7600);
PAINT MONO (-4350 7600);
DISPLAY INVISIBLE (-4350 7600);
FORCEPROP 1 LAST PATH I20
J 2
(-4400 7750);
DISPLAY 0.978723 (-4400 7750);
PAINT WHITE (-4400 7750);
DISPLAY INVISIBLE (-4400 7750);
FORCEPROP 2 LAST CDS_LOCATION C559
J 0
(-4400 7800);
DISPLAY 1.021277 (-4400 7800);
DISPLAY INVISIBLE (-4400 7800);
FORCEPROP 2 LAST $SEC 1
J 0
(-4400 7800);
DISPLAY 0.680851 (-4400 7800);
PAINT MONO (-4400 7800);
DISPLAY INVISIBLE (-4400 7800);
FORCEPROP 2 LAST CDS_SEC 1
J 0
(-4400 7800);
DISPLAY 1.021277 (-4400 7800);
DISPLAY INVISIBLE (-4400 7800);
FORCEADD UNIVERSAL_GND..1
(-4350 7375);
FORCEPROP 3 LASTPIN (-4350 7425) SIG_NAME GND\g
J 0
(-4340 7435);
DISPLAY 0.659574 (-4340 7435);
PAINT MONO (-4340 7435);
DISPLAY INVISIBLE (-4340 7435);
FORCEPROP 2 LAST CDS_LIB logical_power
J 0
(-4350 7375);
PAINT MONO (-4350 7375);
DISPLAY INVISIBLE (-4350 7375);
FORCEPROP 1 LAST HDL_POWER GND
J 1
(-4325 7300);
DISPLAY 0.872340 (-4325 7300);
PAINT GREEN (-4325 7300);
DISPLAY INVISIBLE (-4325 7300);
FORCEPROP 1 LAST PATH I21
J 0
(-4275 7375);
DISPLAY 0.872340 (-4275 7375);
PAINT AQUA (-4275 7375);
DISPLAY INVISIBLE (-4275 7375);
FORCEADD Q_RES..2
R 2
(-4925 7425);
FORCEPROP 1 LAST PART_NUMBER CS12402FB01
J 2
(-4965 7300);
DISPLAY 0.510638 (-4965 7300);
DISPLAY INVISIBLE (-4965 7300);
FORCEPROP 1 LAST VALUE 240
J 2
(-4970 7500);
DISPLAY 0.510638 (-4970 7500);
FORCEPROP 1 LAST TOLERANCE 1%
J 2
(-4970 7450);
DISPLAY 0.510638 (-4970 7450);
FORCEPROP 1 LAST MATERIAL CHIP
J 2
(-4965 7350);
DISPLAY 0.510638 (-4965 7350);
FORCEPROP 1 LAST PACK_TYPE 0402LF
J 2
(-4965 7300);
DISPLAY 0.510638 (-4965 7300);
FORCEPROP 1 LAST WATTAGE 1/16W
J 2
(-4965 7400);
DISPLAY 0.510638 (-4965 7400);
FORCEPROP 1 LAST $LOCATION R911
J 2
(-4945 7550);
DISPLAY 0.978723 (-4945 7550);
FORCEPROP 1 LASTPIN (-4925 7525) $PN 1
J 2
(-4930 7487);
DISPLAY 0.787234 (-4930 7487);
FORCEPROP 1 LASTPIN (-4925 7325) $PN 2
J 2
(-4930 7335);
DISPLAY 0.787234 (-4930 7335);
FORCEPROP 2 LAST CDS_LIB pure_quanta
J 0
(-4925 7425);
PAINT MONO (-4925 7425);
DISPLAY INVISIBLE (-4925 7425);
FORCEPROP 1 LAST PATH I22
J 2
(-4975 7600);
DISPLAY 0.978723 (-4975 7600);
PAINT WHITE (-4975 7600);
DISPLAY INVISIBLE (-4975 7600);
FORCEPROP 2 LAST CDS_LOCATION R911
J 0
(-4975 7650);
DISPLAY 1.021277 (-4975 7650);
DISPLAY INVISIBLE (-4975 7650);
FORCEPROP 2 LAST $SEC 1
J 0
(-4975 7650);
DISPLAY 0.680851 (-4975 7650);
PAINT MONO (-4975 7650);
DISPLAY INVISIBLE (-4975 7650);
FORCEPROP 2 LAST CDS_SEC 1
J 0
(-4975 7650);
DISPLAY 1.021277 (-4975 7650);
DISPLAY INVISIBLE (-4975 7650);
FORCEADD UNIVERSAL_POWER..1
(-5125 7925);
FORCEPROP 3 LASTPIN (-5125 7875) SIG_NAME PVNN_TERM_CPU0\g
J 0
(-5115 7885);
DISPLAY 0.659574 (-5115 7885);
PAINT MONO (-5115 7885);
DISPLAY INVISIBLE (-5115 7885);
FORCEPROP 1 LAST HDL_POWER PVNN_TERM_CPU0
J 1
(-5125 7975);
DISPLAY 0.872340 (-5125 7975);
PAINT GREEN (-5125 7975);
FORCEPROP 2 LAST CDS_LIB logical_power
J 0
(-5125 7925);
PAINT MONO (-5125 7925);
DISPLAY INVISIBLE (-5125 7925);
FORCEPROP 1 LAST PATH I23
J 0
(-5075 7950);
DISPLAY 0.872340 (-5075 7950);
PAINT AQUA (-5075 7950);
DISPLAY INVISIBLE (-5075 7950);
FORCEADD Q_RES..2
R 2
(-5125 7425);
FORCEPROP 1 LAST PART_NUMBER CS12402FB01
J 2
(-5165 7250);
DISPLAY 0.510638 (-5165 7250);
DISPLAY INVISIBLE (-5165 7250);
FORCEPROP 1 LAST VALUE 240
J 2
(-5170 7500);
DISPLAY 0.510638 (-5170 7500);
FORCEPROP 1 LAST WATTAGE 1/16W
J 2
(-5165 7400);
DISPLAY 0.510638 (-5165 7400);
FORCEPROP 1 LAST MATERIAL CHIP
J 2
(-5165 7350);
DISPLAY 0.510638 (-5165 7350);
FORCEPROP 1 LAST PACK_TYPE 0402LF
J 2
(-5165 7300);
DISPLAY 0.510638 (-5165 7300);
FORCEPROP 1 LAST TOLERANCE 1%
J 2
(-5170 7450);
DISPLAY 0.510638 (-5170 7450);
FORCEPROP 1 LAST $LOCATION R910
J 2
(-5170 7550);
DISPLAY 0.978723 (-5170 7550);
FORCEPROP 1 LASTPIN (-5125 7525) $PN 1
J 2
(-5130 7487);
DISPLAY 0.787234 (-5130 7487);
FORCEPROP 1 LASTPIN (-5125 7325) $PN 2
J 2
(-5130 7335);
DISPLAY 0.787234 (-5130 7335);
FORCEPROP 2 LAST CDS_LIB pure_quanta
J 2
(-5125 7425);
PAINT MONO (-5125 7425);
DISPLAY INVISIBLE (-5125 7425);
FORCEPROP 1 LAST PATH I24
J 2
(-5175 7600);
DISPLAY 0.978723 (-5175 7600);
PAINT WHITE (-5175 7600);
DISPLAY INVISIBLE (-5175 7600);
FORCEPROP 2 LAST CDS_LOCATION R910
J 0
(-5175 7650);
DISPLAY 1.021277 (-5175 7650);
DISPLAY INVISIBLE (-5175 7650);
FORCEPROP 2 LAST $SEC 1
J 0
(-5175 7650);
DISPLAY 0.680851 (-5175 7650);
PAINT MONO (-5175 7650);
DISPLAY INVISIBLE (-5175 7650);
FORCEPROP 2 LAST CDS_SEC 1
J 0
(-5175 7650);
DISPLAY 1.021277 (-5175 7650);
DISPLAY INVISIBLE (-5175 7650);
FORCEADD UNIVERSAL_POWER..1
(-3000 6325);
FORCEPROP 3 LASTPIN (-3000 6275) SIG_NAME P3V3_AUX\g
J 0
(-2990 6285);
DISPLAY 0.659574 (-2990 6285);
PAINT MONO (-2990 6285);
DISPLAY INVISIBLE (-2990 6285);
FORCEPROP 1 LAST HDL_POWER P3V3_AUX
J 1
(-3000 6375);
DISPLAY 0.872340 (-3000 6375);
PAINT GREEN (-3000 6375);
FORCEPROP 2 LAST CDS_LIB logical_power
J 0
(-3000 6325);
PAINT MONO (-3000 6325);
DISPLAY INVISIBLE (-3000 6325);
FORCEPROP 1 LAST PATH I30
J 0
(-2950 6350);
DISPLAY 0.872340 (-2950 6350);
PAINT AQUA (-2950 6350);
DISPLAY INVISIBLE (-2950 6350);
FORCEADD Q_CAP..1
(-3000 6000);
FORCEPROP 1 LAST PART_NUMBER CH4104K1B00
J 0
(-2950 5850);
DISPLAY 0.510638 (-2950 5850);
DISPLAY INVISIBLE (-2950 5850);
FORCEPROP 1 LAST TOLERANCE 10%
J 0
(-2950 5950);
DISPLAY 0.510638 (-2950 5950);
FORCEPROP 1 LAST MATERIAL X7R
J 0
(-2950 5900);
DISPLAY 0.510638 (-2950 5900);
FORCEPROP 1 LAST PACK_TYPE 0402
J 0
(-2950 5800);
DISPLAY 0.510638 (-2950 5800);
FORCEPROP 1 LAST VOLTAGE 25V
J 0
(-2950 6000);
DISPLAY 0.510638 (-2950 6000);
FORCEPROP 1 LAST VALUE 0.1UF
J 0
(-2950 6050);
DISPLAY 0.510638 (-2950 6050);
FORCEPROP 1 LAST $LOCATION C562
J 0
(-2950 6100);
DISPLAY 0.978723 (-2950 6100);
FORCEPROP 1 LASTPIN (-3000 6100) $PN 1
J 0
(-2990 6080);
DISPLAY 0.787234 (-2990 6080);
FORCEPROP 1 LASTPIN (-3000 5900) $PN 2
J 0
(-2990 5880);
DISPLAY 0.787234 (-2990 5880);
FORCEPROP 2 LAST CDS_LIB pure_quanta
J 2
(-3000 6000);
PAINT MONO (-3000 6000);
DISPLAY INVISIBLE (-3000 6000);
FORCEPROP 1 LAST PATH I31
J 0
(-2950 6150);
DISPLAY 0.978723 (-2950 6150);
PAINT WHITE (-2950 6150);
DISPLAY INVISIBLE (-2950 6150);
FORCEPROP 2 LAST CDS_LOCATION C562
J 0
(-2950 6200);
DISPLAY 1.021277 (-2950 6200);
DISPLAY INVISIBLE (-2950 6200);
FORCEPROP 2 LAST $SEC 1
J 0
(-2950 6200);
DISPLAY 0.680851 (-2950 6200);
PAINT MONO (-2950 6200);
DISPLAY INVISIBLE (-2950 6200);
FORCEPROP 2 LAST CDS_SEC 1
J 0
(-2950 6200);
DISPLAY 1.021277 (-2950 6200);
DISPLAY INVISIBLE (-2950 6200);
FORCEADD UNIVERSAL_GND..1
(-3000 5775);
FORCEPROP 3 LASTPIN (-3000 5825) SIG_NAME GND\g
J 0
(-2990 5835);
DISPLAY 0.659574 (-2990 5835);
PAINT MONO (-2990 5835);
DISPLAY INVISIBLE (-2990 5835);
FORCEPROP 2 LAST CDS_LIB logical_power
J 0
(-3000 5775);
PAINT MONO (-3000 5775);
DISPLAY INVISIBLE (-3000 5775);
FORCEPROP 1 LAST HDL_POWER GND
J 1
(-2975 5700);
DISPLAY 0.872340 (-2975 5700);
PAINT GREEN (-2975 5700);
DISPLAY INVISIBLE (-2975 5700);
FORCEPROP 1 LAST PATH I32
J 0
(-2925 5775);
DISPLAY 0.872340 (-2925 5775);
PAINT AQUA (-2925 5775);
DISPLAY INVISIBLE (-2925 5775);
FORCEADD UNIVERSAL_POWER..1
(-2500 4575);
FORCEPROP 3 LASTPIN (-2500 4525) SIG_NAME P3V3\g
J 0
(-2490 4535);
DISPLAY 0.659574 (-2490 4535);
PAINT MONO (-2490 4535);
DISPLAY INVISIBLE (-2490 4535);
FORCEPROP 1 LAST HDL_POWER P3V3
J 1
(-2500 4625);
DISPLAY 0.872340 (-2500 4625);
PAINT GREEN (-2500 4625);
FORCEPROP 2 LAST CDS_LIB logical_power
J 0
(-2500 4575);
PAINT MONO (-2500 4575);
DISPLAY INVISIBLE (-2500 4575);
FORCEPROP 1 LAST PATH I33
J 0
(-2450 4600);
DISPLAY 0.872340 (-2450 4600);
PAINT AQUA (-2450 4600);
DISPLAY INVISIBLE (-2450 4600);
FORCEADD Q_RES..2
(-2500 4325);
FORCEPROP 1 LAST PART_NUMBER CS24702JB10
J 0
(-2460 4150);
DISPLAY 0.510638 (-2460 4150);
DISPLAY INVISIBLE (-2460 4150);
FORCEPROP 1 LAST TOLERANCE 5%
J 0
(-2455 4350);
DISPLAY 0.510638 (-2455 4350);
FORCEPROP 1 LAST MATERIAL CHIP
J 0
(-2460 4250);
DISPLAY 0.510638 (-2460 4250);
FORCEPROP 1 LAST WATTAGE 1/16W
J 0
(-2460 4300);
DISPLAY 0.510638 (-2460 4300);
FORCEPROP 1 LAST VALUE 4.7K
J 0
(-2455 4400);
DISPLAY 0.510638 (-2455 4400);
FORCEPROP 1 LAST PACK_TYPE 0402LF
J 0
(-2460 4200);
DISPLAY 0.510638 (-2460 4200);
FORCEPROP 1 LAST $LOCATION R1002
J 0
(-2455 4450);
DISPLAY 0.787234 (-2455 4450);
FORCEPROP 1 LASTPIN (-2500 4425) $PN 1
J 0
(-2495 4387);
DISPLAY 0.787234 (-2495 4387);
FORCEPROP 1 LASTPIN (-2500 4225) $PN 2
J 0
(-2495 4235);
DISPLAY 0.787234 (-2495 4235);
FORCEPROP 2 LAST CDS_LIB pure_quanta
J 0
(-2500 4325);
PAINT MONO (-2500 4325);
DISPLAY INVISIBLE (-2500 4325);
FORCEPROP 1 LAST PATH I34
J 0
(-2450 4500);
DISPLAY 0.978723 (-2450 4500);
PAINT WHITE (-2450 4500);
DISPLAY INVISIBLE (-2450 4500);
FORCEPROP 2 LAST CDS_LOCATION R1002
J 0
(-2450 4550);
DISPLAY 1.021277 (-2450 4550);
DISPLAY INVISIBLE (-2450 4550);
FORCEPROP 2 LAST $SEC 1
J 0
(-2450 4550);
DISPLAY 0.680851 (-2450 4550);
PAINT MONO (-2450 4550);
DISPLAY INVISIBLE (-2450 4550);
FORCEPROP 2 LAST CDS_SEC 1
J 0
(-2450 4550);
DISPLAY 1.021277 (-2450 4550);
DISPLAY INVISIBLE (-2450 4550);
FORCEADD UNIVERSAL_GND..1
(-2500 3500);
FORCEPROP 3 LASTPIN (-2500 3550) SIG_NAME GND\g
J 0
(-2490 3560);
DISPLAY 0.659574 (-2490 3560);
PAINT MONO (-2490 3560);
DISPLAY INVISIBLE (-2490 3560);
FORCEPROP 2 LAST CDS_LIB logical_power
J 0
(-2500 3500);
DISPLAY INVISIBLE (-2500 3500);
FORCEPROP 1 LAST HDL_POWER GND
J 1
(-2475 3425);
DISPLAY 0.872340 (-2475 3425);
PAINT GREEN (-2475 3425);
DISPLAY INVISIBLE (-2475 3425);
FORCEPROP 1 LAST PATH I35
J 0
(-2425 3500);
DISPLAY 0.872340 (-2425 3500);
PAINT AQUA (-2425 3500);
DISPLAY INVISIBLE (-2425 3500);
FORCEADD UNIVERSAL_POWER..1
(-2500 3275);
FORCEPROP 3 LASTPIN (-2500 3225) SIG_NAME P3V3\g
J 0
(-2490 3235);
DISPLAY 0.659574 (-2490 3235);
PAINT MONO (-2490 3235);
DISPLAY INVISIBLE (-2490 3235);
FORCEPROP 1 LAST HDL_POWER P3V3
J 1
(-2500 3325);
DISPLAY 0.872340 (-2500 3325);
PAINT GREEN (-2500 3325);
FORCEPROP 2 LAST CDS_LIB logical_power
J 0
(-2500 3275);
PAINT MONO (-2500 3275);
DISPLAY INVISIBLE (-2500 3275);
FORCEPROP 1 LAST PATH I37
J 0
(-2450 3300);
DISPLAY 0.872340 (-2450 3300);
PAINT AQUA (-2450 3300);
DISPLAY INVISIBLE (-2450 3300);
FORCEADD Q_RES..2
(-2500 3025);
FORCEPROP 1 LAST PART_NUMBER CS24702JB10
J 0
(-2460 2850);
DISPLAY 0.510638 (-2460 2850);
DISPLAY INVISIBLE (-2460 2850);
FORCEPROP 1 LAST VALUE 4.7K
J 0
(-2455 3100);
DISPLAY 0.510638 (-2455 3100);
FORCEPROP 1 LAST MATERIAL CHIP
J 0
(-2460 2950);
DISPLAY 0.510638 (-2460 2950);
FORCEPROP 1 LAST WATTAGE 1/16W
J 0
(-2460 3000);
DISPLAY 0.510638 (-2460 3000);
FORCEPROP 1 LAST TOLERANCE 5%
J 0
(-2455 3050);
DISPLAY 0.510638 (-2455 3050);
FORCEPROP 1 LAST PACK_TYPE 0402LF
J 0
(-2460 2900);
DISPLAY 0.510638 (-2460 2900);
FORCEPROP 1 LAST $LOCATION R1003
J 0
(-2455 3150);
DISPLAY 0.787234 (-2455 3150);
FORCEPROP 1 LASTPIN (-2500 3125) $PN 1
J 0
(-2495 3087);
DISPLAY 0.787234 (-2495 3087);
FORCEPROP 1 LASTPIN (-2500 2925) $PN 2
J 0
(-2495 2935);
DISPLAY 0.787234 (-2495 2935);
FORCEPROP 2 LAST CDS_LIB pure_quanta
J 0
(-2500 3025);
PAINT MONO (-2500 3025);
DISPLAY INVISIBLE (-2500 3025);
FORCEPROP 1 LAST PATH I38
J 0
(-2450 3200);
DISPLAY 0.978723 (-2450 3200);
PAINT WHITE (-2450 3200);
DISPLAY INVISIBLE (-2450 3200);
FORCEPROP 2 LAST CDS_LOCATION R1003
J 0
(-2450 3250);
DISPLAY 1.021277 (-2450 3250);
DISPLAY INVISIBLE (-2450 3250);
FORCEPROP 2 LAST $SEC 1
J 0
(-2450 3250);
DISPLAY 0.680851 (-2450 3250);
PAINT MONO (-2450 3250);
DISPLAY INVISIBLE (-2450 3250);
FORCEPROP 2 LAST CDS_SEC 1
J 0
(-2450 3250);
DISPLAY 1.021277 (-2450 3250);
DISPLAY INVISIBLE (-2450 3250);
FORCEADD PCA9617ADP..1
(-3675 7075);
FORCEPROP 1 LAST PART_NUMBER AL009617K02
J 0
(-3949 7435);
DISPLAY 0.723404 (-3949 7435);
PAINT GREEN (-3949 7435);
DISPLAY INVISIBLE (-3949 7435);
FORCEPROP 2 LAST PART_TYPE SMLF
J 0
(-3925 7575);
DISPLAY 1.021277 (-3925 7575);
FORCEPROP 1 LAST MATERIAL IC
J 0
(-3949 7380);
DISPLAY 0.723404 (-3949 7380);
PAINT GREEN (-3949 7380);
FORCEPROP 2 LAST VALUE PCA9617ADP
J 0
(-3925 7525);
DISPLAY 1.021277 (-3925 7525);
FORCEPROP 1 LAST $LOCATION U28
J 0
(-3949 7485);
DISPLAY 0.723404 (-3949 7485);
PAINT GREEN (-3949 7485);
FORCEPROP 2 LASTPIN (-3250 6875) $PN 5
J 0
(-3240 6885);
DISPLAY 0.808511 (-3240 6885);
FORCEPROP 2 LASTPIN (-4100 6875) $PN 4
J 2
(-4110 6885);
DISPLAY 0.808511 (-4110 6885);
FORCEPROP 2 LASTPIN (-4100 7125) $PN 2
J 2
(-4110 7135);
DISPLAY 0.808511 (-4110 7135);
FORCEPROP 2 LASTPIN (-3250 7125) $PN 7
J 0
(-3240 7135);
DISPLAY 0.808511 (-3240 7135);
FORCEPROP 2 LASTPIN (-4100 7025) $PN 3
J 2
(-4110 7035);
DISPLAY 0.808511 (-4110 7035);
FORCEPROP 2 LASTPIN (-3250 7025) $PN 6
J 0
(-3240 7035);
DISPLAY 0.808511 (-3240 7035);
FORCEPROP 2 LASTPIN (-4100 7275) $PN 1
J 2
(-4110 7285);
DISPLAY 0.808511 (-4110 7285);
FORCEPROP 2 LASTPIN (-3250 7275) $PN 8
J 0
(-3240 7285);
DISPLAY 0.808511 (-3240 7285);
FORCEPROP 2 LAST SEC_TYPE 
J 0
(-3925 7625);
DISPLAY 1.021277 (-3925 7625);
DISPLAY INVISIBLE (-3925 7625);
FORCEPROP 1 LAST CDS_LMAN_SYM_OUTLINE -275,300,275,-300
J 0
(-3675 7075);
DISPLAY 0.468085 (-3675 7075);
PAINT GREEN (-3675 7075);
DISPLAY INVISIBLE (-3675 7075);
FORCEPROP 1 LAST NEEDS_NO_SIZE TRUE
J 0
(-3400 6775);
DISPLAY 0.468085 (-3400 6775);
PAINT GREEN (-3400 6775);
DISPLAY INVISIBLE (-3400 6775);
FORCEPROP 2 LAST CDS_LIB pure_quanta
J 0
(-3675 7075);
PAINT MONO (-3675 7075);
DISPLAY INVISIBLE (-3675 7075);
FORCEPROP 1 LAST PATH I39
J 0
(-3675 7075);
DISPLAY 0.723404 (-3675 7075);
PAINT GREEN (-3675 7075);
DISPLAY INVISIBLE (-3675 7075);
FORCEPROP 2 LAST CDS_LOCATION U28
J 0
(-3925 7625);
DISPLAY 1.021277 (-3925 7625);
DISPLAY INVISIBLE (-3925 7625);
FORCEPROP 2 LAST SEC 1
J 0
(-3925 7625);
DISPLAY 0.680851 (-3925 7625);
PAINT MONO (-3925 7625);
DISPLAY INVISIBLE (-3925 7625);
FORCEADD UNIVERSAL_GND..1
(-4200 6650);
FORCEPROP 3 LASTPIN (-4200 6700) SIG_NAME GND\g
J 0
(-4190 6710);
DISPLAY 0.659574 (-4190 6710);
PAINT MONO (-4190 6710);
DISPLAY INVISIBLE (-4190 6710);
FORCEPROP 2 LAST CDS_LIB logical_power
J 0
(-4200 6650);
PAINT MONO (-4200 6650);
DISPLAY INVISIBLE (-4200 6650);
FORCEPROP 1 LAST HDL_POWER GND
J 1
(-4175 6575);
DISPLAY 0.872340 (-4175 6575);
PAINT GREEN (-4175 6575);
DISPLAY INVISIBLE (-4175 6575);
FORCEPROP 1 LAST PATH I40
J 0
(-4125 6650);
DISPLAY 0.872340 (-4125 6650);
PAINT AQUA (-4125 6650);
DISPLAY INVISIBLE (-4125 6650);
FORCEADD UNIVERSAL_POWER..1
(-4350 6325);
FORCEPROP 3 LASTPIN (-4350 6275) SIG_NAME PVNN_TERM_CPU1\g
J 0
(-4340 6285);
DISPLAY 0.659574 (-4340 6285);
PAINT MONO (-4340 6285);
DISPLAY INVISIBLE (-4340 6285);
FORCEPROP 1 LAST HDL_POWER PVNN_TERM_CPU1
J 1
(-4350 6375);
DISPLAY 0.872340 (-4350 6375);
PAINT GREEN (-4350 6375);
FORCEPROP 2 LAST CDS_LIB logical_power
J 0
(-4350 6325);
PAINT MONO (-4350 6325);
DISPLAY INVISIBLE (-4350 6325);
FORCEPROP 1 LAST PATH I41
J 0
(-4300 6350);
DISPLAY 0.872340 (-4300 6350);
PAINT AQUA (-4300 6350);
DISPLAY INVISIBLE (-4300 6350);
FORCEADD Q_CAP..1
R 2
(-4350 6000);
FORCEPROP 1 LAST PART_NUMBER CH4104K1B00
J 2
(-4400 5850);
DISPLAY 0.510638 (-4400 5850);
DISPLAY INVISIBLE (-4400 5850);
FORCEPROP 1 LAST VALUE 0.1UF
J 2
(-4400 6050);
DISPLAY 0.510638 (-4400 6050);
FORCEPROP 1 LAST TOLERANCE 10%
J 2
(-4400 5950);
DISPLAY 0.510638 (-4400 5950);
FORCEPROP 1 LAST PACK_TYPE 0402
J 2
(-4400 5800);
DISPLAY 0.510638 (-4400 5800);
FORCEPROP 1 LAST MATERIAL X7R
J 2
(-4400 5900);
DISPLAY 0.510638 (-4400 5900);
FORCEPROP 1 LAST VOLTAGE 25V
J 2
(-4400 6000);
DISPLAY 0.510638 (-4400 6000);
FORCEPROP 1 LAST $LOCATION C560
J 2
(-4400 6100);
DISPLAY 0.978723 (-4400 6100);
FORCEPROP 1 LASTPIN (-4350 6100) $PN 1
J 2
(-4360 6080);
DISPLAY 0.787234 (-4360 6080);
FORCEPROP 1 LASTPIN (-4350 5900) $PN 2
J 2
(-4360 5880);
DISPLAY 0.787234 (-4360 5880);
FORCEPROP 2 LAST CDS_LIB pure_quanta
J 2
(-4350 6000);
PAINT MONO (-4350 6000);
DISPLAY INVISIBLE (-4350 6000);
FORCEPROP 1 LAST PATH I42
J 2
(-4400 6150);
DISPLAY 0.978723 (-4400 6150);
PAINT WHITE (-4400 6150);
DISPLAY INVISIBLE (-4400 6150);
FORCEPROP 2 LAST CDS_LOCATION C560
J 0
(-4400 6200);
DISPLAY 1.021277 (-4400 6200);
DISPLAY INVISIBLE (-4400 6200);
FORCEPROP 2 LAST $SEC 1
J 0
(-4400 6200);
DISPLAY 0.680851 (-4400 6200);
PAINT MONO (-4400 6200);
DISPLAY INVISIBLE (-4400 6200);
FORCEPROP 2 LAST CDS_SEC 1
J 0
(-4400 6200);
DISPLAY 1.021277 (-4400 6200);
DISPLAY INVISIBLE (-4400 6200);
FORCEADD PCA9617ADP..1
(-3675 5475);
FORCEPROP 1 LAST PART_NUMBER AL009617K02
J 0
(-3949 5835);
DISPLAY 0.723404 (-3949 5835);
PAINT GREEN (-3949 5835);
DISPLAY INVISIBLE (-3949 5835);
FORCEPROP 2 LAST PART_TYPE SMLF
J 0
(-3925 5975);
DISPLAY 1.021277 (-3925 5975);
FORCEPROP 1 LAST MATERIAL IC
J 0
(-3949 5780);
DISPLAY 0.723404 (-3949 5780);
PAINT GREEN (-3949 5780);
FORCEPROP 2 LAST VALUE PCA9617ADP
J 0
(-3925 5925);
DISPLAY 1.021277 (-3925 5925);
FORCEPROP 1 LAST $LOCATION U29
J 0
(-3949 5885);
DISPLAY 0.723404 (-3949 5885);
PAINT GREEN (-3949 5885);
FORCEPROP 2 LASTPIN (-3250 5275) $PN 5
J 0
(-3240 5285);
DISPLAY 0.808511 (-3240 5285);
FORCEPROP 2 LASTPIN (-4100 5275) $PN 4
J 2
(-4110 5285);
DISPLAY 0.808511 (-4110 5285);
FORCEPROP 2 LASTPIN (-4100 5525) $PN 2
J 2
(-4110 5535);
DISPLAY 0.808511 (-4110 5535);
FORCEPROP 2 LASTPIN (-3250 5525) $PN 7
J 0
(-3240 5535);
DISPLAY 0.808511 (-3240 5535);
FORCEPROP 2 LASTPIN (-4100 5425) $PN 3
J 2
(-4110 5435);
DISPLAY 0.808511 (-4110 5435);
FORCEPROP 2 LASTPIN (-3250 5425) $PN 6
J 0
(-3240 5435);
DISPLAY 0.808511 (-3240 5435);
FORCEPROP 2 LASTPIN (-4100 5675) $PN 1
J 2
(-4110 5685);
DISPLAY 0.808511 (-4110 5685);
FORCEPROP 2 LASTPIN (-3250 5675) $PN 8
J 0
(-3240 5685);
DISPLAY 0.808511 (-3240 5685);
FORCEPROP 2 LAST CDS_LIB pure_quanta
J 0
(-3675 5475);
PAINT MONO (-3675 5475);
DISPLAY INVISIBLE (-3675 5475);
FORCEPROP 1 LAST NEEDS_NO_SIZE TRUE
J 0
(-3400 5175);
DISPLAY 0.468085 (-3400 5175);
PAINT GREEN (-3400 5175);
DISPLAY INVISIBLE (-3400 5175);
FORCEPROP 1 LAST CDS_LMAN_SYM_OUTLINE -275,300,275,-300
J 0
(-3675 5475);
DISPLAY 0.468085 (-3675 5475);
PAINT GREEN (-3675 5475);
DISPLAY INVISIBLE (-3675 5475);
FORCEPROP 2 LAST SEC_TYPE 
J 0
(-3925 6025);
DISPLAY 1.021277 (-3925 6025);
DISPLAY INVISIBLE (-3925 6025);
FORCEPROP 1 LAST PATH I43
J 0
(-3675 5475);
DISPLAY 0.723404 (-3675 5475);
PAINT GREEN (-3675 5475);
DISPLAY INVISIBLE (-3675 5475);
FORCEPROP 2 LAST CDS_LOCATION U29
J 0
(-3925 6025);
DISPLAY 1.021277 (-3925 6025);
DISPLAY INVISIBLE (-3925 6025);
FORCEPROP 2 LAST SEC 1
J 0
(-3925 6025);
DISPLAY 0.680851 (-3925 6025);
PAINT MONO (-3925 6025);
DISPLAY INVISIBLE (-3925 6025);
FORCEADD UNIVERSAL_GND..1
(-4350 5775);
FORCEPROP 3 LASTPIN (-4350 5825) SIG_NAME GND\g
J 0
(-4340 5835);
DISPLAY 0.659574 (-4340 5835);
PAINT MONO (-4340 5835);
DISPLAY INVISIBLE (-4340 5835);
FORCEPROP 2 LAST CDS_LIB logical_power
J 0
(-4350 5775);
PAINT MONO (-4350 5775);
DISPLAY INVISIBLE (-4350 5775);
FORCEPROP 1 LAST HDL_POWER GND
J 1
(-4325 5700);
DISPLAY 0.872340 (-4325 5700);
PAINT GREEN (-4325 5700);
DISPLAY INVISIBLE (-4325 5700);
FORCEPROP 1 LAST PATH I44
J 0
(-4275 5775);
DISPLAY 0.872340 (-4275 5775);
PAINT AQUA (-4275 5775);
DISPLAY INVISIBLE (-4275 5775);
FORCEADD UNIVERSAL_GND..1
(-4200 5050);
FORCEPROP 3 LASTPIN (-4200 5100) SIG_NAME GND\g
J 0
(-4190 5110);
DISPLAY 0.659574 (-4190 5110);
PAINT MONO (-4190 5110);
DISPLAY INVISIBLE (-4190 5110);
FORCEPROP 2 LAST CDS_LIB logical_power
J 0
(-4200 5050);
PAINT MONO (-4200 5050);
DISPLAY INVISIBLE (-4200 5050);
FORCEPROP 1 LAST HDL_POWER GND
J 1
(-4175 4975);
DISPLAY 0.872340 (-4175 4975);
PAINT GREEN (-4175 4975);
DISPLAY INVISIBLE (-4175 4975);
FORCEPROP 1 LAST PATH I45
J 0
(-4125 5050);
DISPLAY 0.872340 (-4125 5050);
PAINT AQUA (-4125 5050);
DISPLAY INVISIBLE (-4125 5050);
FORCEADD Q_RES..2
R 2
(-4900 5825);
FORCEPROP 1 LAST PART_NUMBER CS12402FB01
J 2
(-4940 5700);
DISPLAY 0.510638 (-4940 5700);
DISPLAY INVISIBLE (-4940 5700);
FORCEPROP 1 LAST MATERIAL CHIP
J 2
(-4940 5750);
DISPLAY 0.510638 (-4940 5750);
FORCEPROP 1 LAST TOLERANCE 1%
J 2
(-4945 5850);
DISPLAY 0.510638 (-4945 5850);
FORCEPROP 1 LAST VALUE 240
J 2
(-4945 5900);
DISPLAY 0.510638 (-4945 5900);
FORCEPROP 1 LAST PACK_TYPE 0402LF
J 2
(-4940 5700);
DISPLAY 0.510638 (-4940 5700);
FORCEPROP 1 LAST WATTAGE 1/16W
J 2
(-4940 5800);
DISPLAY 0.510638 (-4940 5800);
FORCEPROP 1 LAST $LOCATION R964
J 2
(-4945 5950);
DISPLAY 0.978723 (-4945 5950);
FORCEPROP 1 LASTPIN (-4900 5925) $PN 1
J 2
(-4905 5887);
DISPLAY 0.787234 (-4905 5887);
FORCEPROP 1 LASTPIN (-4900 5725) $PN 2
J 2
(-4905 5735);
DISPLAY 0.787234 (-4905 5735);
FORCEPROP 2 LAST CDS_LIB pure_quanta
J 0
(-4900 5825);
PAINT MONO (-4900 5825);
DISPLAY INVISIBLE (-4900 5825);
FORCEPROP 1 LAST PATH I46
J 2
(-4950 6000);
DISPLAY 0.978723 (-4950 6000);
PAINT WHITE (-4950 6000);
DISPLAY INVISIBLE (-4950 6000);
FORCEPROP 2 LAST CDS_LOCATION R964
J 0
(-4950 6050);
DISPLAY 1.021277 (-4950 6050);
DISPLAY INVISIBLE (-4950 6050);
FORCEPROP 2 LAST $SEC 1
J 0
(-4950 6050);
DISPLAY 0.680851 (-4950 6050);
PAINT MONO (-4950 6050);
DISPLAY INVISIBLE (-4950 6050);
FORCEPROP 2 LAST CDS_SEC 1
J 0
(-4950 6050);
DISPLAY 1.021277 (-4950 6050);
DISPLAY INVISIBLE (-4950 6050);
FORCEADD UNIVERSAL_POWER..1
(-5125 6325);
FORCEPROP 3 LASTPIN (-5125 6275) SIG_NAME PVNN_TERM_CPU1\g
J 0
(-5115 6285);
DISPLAY 0.659574 (-5115 6285);
PAINT MONO (-5115 6285);
DISPLAY INVISIBLE (-5115 6285);
FORCEPROP 1 LAST HDL_POWER PVNN_TERM_CPU1
J 1
(-5125 6375);
DISPLAY 0.872340 (-5125 6375);
PAINT GREEN (-5125 6375);
FORCEPROP 2 LAST CDS_LIB logical_power
J 0
(-5125 6325);
PAINT MONO (-5125 6325);
DISPLAY INVISIBLE (-5125 6325);
FORCEPROP 1 LAST PATH I47
J 0
(-5075 6350);
DISPLAY 0.872340 (-5075 6350);
PAINT AQUA (-5075 6350);
DISPLAY INVISIBLE (-5075 6350);
FORCEADD Q_RES..2
R 2
(-5125 5825);
FORCEPROP 1 LAST PART_NUMBER CS12402FB01
J 2
(-5165 5650);
DISPLAY 0.510638 (-5165 5650);
DISPLAY INVISIBLE (-5165 5650);
FORCEPROP 1 LAST VALUE 240
J 2
(-5170 5900);
DISPLAY 0.510638 (-5170 5900);
FORCEPROP 1 LAST TOLERANCE 1%
J 2
(-5170 5850);
DISPLAY 0.510638 (-5170 5850);
FORCEPROP 1 LAST WATTAGE 1/16W
J 2
(-5165 5800);
DISPLAY 0.510638 (-5165 5800);
FORCEPROP 1 LAST MATERIAL CHIP
J 2
(-5165 5750);
DISPLAY 0.510638 (-5165 5750);
FORCEPROP 1 LAST PACK_TYPE 0402LF
J 2
(-5165 5700);
DISPLAY 0.510638 (-5165 5700);
FORCEPROP 1 LAST $LOCATION R963
J 2
(-5170 5950);
DISPLAY 0.978723 (-5170 5950);
FORCEPROP 1 LASTPIN (-5125 5925) $PN 1
J 2
(-5130 5887);
DISPLAY 0.787234 (-5130 5887);
FORCEPROP 1 LASTPIN (-5125 5725) $PN 2
J 2
(-5130 5735);
DISPLAY 0.787234 (-5130 5735);
FORCEPROP 2 LAST CDS_LIB pure_quanta
J 2
(-5125 5825);
PAINT MONO (-5125 5825);
DISPLAY INVISIBLE (-5125 5825);
FORCEPROP 1 LAST PATH I48
J 2
(-5175 6000);
DISPLAY 0.978723 (-5175 6000);
PAINT WHITE (-5175 6000);
DISPLAY INVISIBLE (-5175 6000);
FORCEPROP 2 LAST CDS_LOCATION R963
J 0
(-5175 6050);
DISPLAY 1.021277 (-5175 6050);
DISPLAY INVISIBLE (-5175 6050);
FORCEPROP 2 LAST $SEC 1
J 0
(-5175 6050);
DISPLAY 0.680851 (-5175 6050);
PAINT MONO (-5175 6050);
DISPLAY INVISIBLE (-5175 6050);
FORCEPROP 2 LAST CDS_SEC 1
J 0
(-5175 6050);
DISPLAY 1.021277 (-5175 6050);
DISPLAY INVISIBLE (-5175 6050);
FORCEADD OFFPAGE..2
(-600 4075);
FORCEPROP 2 LAST $XR0 14 
J 0
(-411 4075);
DISPLAY 0.638298 (-411 4075);
PAINT MONO (-411 4075);
FORCEPROP 2 LAST CDS_LIB standard
J 0
(-600 4075);
DISPLAY INVISIBLE (-600 4075);
FORCEPROP 1 LAST OFFPAGE TRUE
J 0
(-275 3950);
DISPLAY 0.872340 (-275 3950);
PAINT GREEN (-275 3950);
DISPLAY INVISIBLE (-275 3950);
FORCEPROP 1 LAST COMMENT_BODY TRUE
J 0
(-645 3980);
DISPLAY 0.872340 (-645 3980);
PAINT GREEN (-645 3980);
DISPLAY INVISIBLE (-645 3980);
FORCEPROP 2 LAST PATH I5
J 0
(-400 4125);
DISPLAY 1.021277 (-400 4125);
DISPLAY INVISIBLE (-400 4125);
FORCEADD UNIVERSAL_POWER..1
(-3975 4575);
FORCEPROP 3 LASTPIN (-3975 4525) SIG_NAME P3V3\g
J 0
(-3965 4535);
DISPLAY 0.659574 (-3965 4535);
PAINT MONO (-3965 4535);
DISPLAY INVISIBLE (-3965 4535);
FORCEPROP 1 LAST HDL_POWER P3V3
J 1
(-3975 4625);
DISPLAY 0.872340 (-3975 4625);
PAINT GREEN (-3975 4625);
FORCEPROP 2 LAST CDS_LIB logical_power
J 0
(-3975 4575);
PAINT MONO (-3975 4575);
DISPLAY INVISIBLE (-3975 4575);
FORCEPROP 1 LAST PATH I51
J 0
(-3925 4600);
DISPLAY 0.872340 (-3925 4600);
PAINT AQUA (-3925 4600);
DISPLAY INVISIBLE (-3925 4600);
FORCEADD Q_RES..2
(-3975 4325);
FORCEPROP 1 LAST PART_NUMBER CS24702JB10
J 0
(-3935 4200);
DISPLAY 0.510638 (-3935 4200);
DISPLAY INVISIBLE (-3935 4200);
FORCEPROP 1 LAST PACK_TYPE 0402LF
J 0
(-3935 4200);
DISPLAY 0.510638 (-3935 4200);
FORCEPROP 1 LAST MATERIAL CHIP
J 0
(-3935 4250);
DISPLAY 0.510638 (-3935 4250);
FORCEPROP 1 LAST TOLERANCE 5%
J 0
(-3930 4350);
DISPLAY 0.510638 (-3930 4350);
FORCEPROP 1 LAST VALUE 4.7K
J 0
(-3930 4400);
DISPLAY 0.510638 (-3930 4400);
FORCEPROP 1 LAST WATTAGE 1/16W
J 0
(-3935 4300);
DISPLAY 0.510638 (-3935 4300);
FORCEPROP 1 LAST $LOCATION R1000
J 0
(-3930 4450);
DISPLAY 0.787234 (-3930 4450);
FORCEPROP 1 LASTPIN (-3975 4425) $PN 1
J 0
(-3970 4387);
DISPLAY 0.787234 (-3970 4387);
FORCEPROP 1 LASTPIN (-3975 4225) $PN 2
J 0
(-3970 4235);
DISPLAY 0.787234 (-3970 4235);
FORCEPROP 2 LAST CDS_LIB pure_quanta
J 0
(-3975 4325);
PAINT MONO (-3975 4325);
DISPLAY INVISIBLE (-3975 4325);
FORCEPROP 1 LAST PATH I52
J 0
(-3925 4500);
DISPLAY 0.978723 (-3925 4500);
PAINT WHITE (-3925 4500);
DISPLAY INVISIBLE (-3925 4500);
FORCEPROP 2 LAST CDS_LOCATION R1000
J 0
(-3925 4550);
DISPLAY 1.021277 (-3925 4550);
DISPLAY INVISIBLE (-3925 4550);
FORCEPROP 2 LAST $SEC 1
J 0
(-3925 4550);
DISPLAY 0.680851 (-3925 4550);
PAINT MONO (-3925 4550);
DISPLAY INVISIBLE (-3925 4550);
FORCEPROP 2 LAST CDS_SEC 1
J 0
(-3925 4550);
DISPLAY 1.021277 (-3925 4550);
DISPLAY INVISIBLE (-3925 4550);
FORCEADD Q_RES..1
(-4325 3750);
FORCEPROP 1 LAST PART_NUMBER CS00002JB13
J 0
(-4425 3825);
DISPLAY 0.510638 (-4425 3825);
DISPLAY INVISIBLE (-4425 3825);
FORCEPROP 1 LAST MATERIAL CHIP
J 0
(-4425 3875);
DISPLAY 0.510638 (-4425 3875);
FORCEPROP 1 LAST PACK_TYPE 0402LF
J 0
(-4425 3925);
DISPLAY 0.510638 (-4425 3925);
FORCEPROP 1 LAST VALUE 0
J 2
(-4175 3750);
DISPLAY 0.638298 (-4175 3750);
FORCEPROP 1 LAST TOLERANCE 5%
J 0
(-4150 3750);
DISPLAY 0.638298 (-4150 3750);
FORCEPROP 1 LAST WATTAGE 1/16W
J 2
(-4200 3875);
DISPLAY 0.510638 (-4200 3875);
FORCEPROP 1 LAST $LOCATION R998
J 0
(-4525 3750);
DISPLAY 0.638298 (-4525 3750);
FORCEPROP 1 LASTPIN (-4425 3750) $PN 1
J 0
(-4413 3762);
DISPLAY 0.787234 (-4413 3762);
FORCEPROP 1 LASTPIN (-4225 3750) $PN 2
J 0
(-4263 3762);
DISPLAY 0.787234 (-4263 3762);
FORCEPROP 2 LAST CDS_LIB pure_quanta
J 0
(-4325 3750);
PAINT MONO (-4325 3750);
DISPLAY INVISIBLE (-4325 3750);
FORCEPROP 1 LAST PATH I53
J 0
(-4375 3900);
DISPLAY 0.978723 (-4375 3900);
PAINT WHITE (-4375 3900);
DISPLAY INVISIBLE (-4375 3900);
FORCEPROP 2 LAST CDS_LOCATION R998
J 0
(-4375 3950);
DISPLAY 1.021277 (-4375 3950);
DISPLAY INVISIBLE (-4375 3950);
FORCEPROP 2 LAST $SEC 1
J 0
(-4375 3950);
DISPLAY 0.680851 (-4375 3950);
PAINT MONO (-4375 3950);
DISPLAY INVISIBLE (-4375 3950);
FORCEPROP 2 LAST CDS_SEC 1
J 0
(-4375 3950);
DISPLAY 1.021277 (-4375 3950);
DISPLAY INVISIBLE (-4375 3950);
FORCEADD UNIVERSAL_POWER..1
(-3975 3275);
FORCEPROP 3 LASTPIN (-3975 3225) SIG_NAME P3V3\g
J 0
(-3965 3235);
DISPLAY 0.659574 (-3965 3235);
PAINT MONO (-3965 3235);
DISPLAY INVISIBLE (-3965 3235);
FORCEPROP 1 LAST HDL_POWER P3V3
J 1
(-3975 3325);
DISPLAY 0.872340 (-3975 3325);
PAINT GREEN (-3975 3325);
FORCEPROP 2 LAST CDS_LIB logical_power
J 0
(-3975 3275);
PAINT MONO (-3975 3275);
DISPLAY INVISIBLE (-3975 3275);
FORCEPROP 1 LAST PATH I54
J 0
(-3925 3300);
DISPLAY 0.872340 (-3925 3300);
PAINT AQUA (-3925 3300);
DISPLAY INVISIBLE (-3925 3300);
FORCEADD Q_RES..2
(-3975 3025);
FORCEPROP 1 LAST PART_NUMBER CS24702JB10
J 0
(-3935 2900);
DISPLAY 0.510638 (-3935 2900);
DISPLAY INVISIBLE (-3935 2900);
FORCEPROP 1 LAST VALUE 4.7K
J 0
(-3930 3100);
DISPLAY 0.510638 (-3930 3100);
FORCEPROP 1 LAST MATERIAL CHIP
J 0
(-3935 2950);
DISPLAY 0.510638 (-3935 2950);
FORCEPROP 1 LAST WATTAGE 1/16W
J 0
(-3935 3000);
DISPLAY 0.510638 (-3935 3000);
FORCEPROP 1 LAST TOLERANCE 5%
J 0
(-3930 3050);
DISPLAY 0.510638 (-3930 3050);
FORCEPROP 1 LAST PACK_TYPE 0402LF
J 0
(-3935 2900);
DISPLAY 0.510638 (-3935 2900);
FORCEPROP 1 LAST $LOCATION R1001
J 0
(-3930 3150);
DISPLAY 0.787234 (-3930 3150);
FORCEPROP 1 LASTPIN (-3975 3125) $PN 1
J 0
(-3970 3087);
DISPLAY 0.787234 (-3970 3087);
FORCEPROP 1 LASTPIN (-3975 2925) $PN 2
J 0
(-3970 2935);
DISPLAY 0.787234 (-3970 2935);
FORCEPROP 2 LAST CDS_LIB pure_quanta
J 0
(-3975 3025);
PAINT MONO (-3975 3025);
DISPLAY INVISIBLE (-3975 3025);
FORCEPROP 1 LAST PATH I55
J 0
(-3925 3200);
DISPLAY 0.978723 (-3925 3200);
PAINT WHITE (-3925 3200);
DISPLAY INVISIBLE (-3925 3200);
FORCEPROP 2 LAST CDS_LOCATION R1001
J 0
(-3925 3250);
DISPLAY 1.021277 (-3925 3250);
DISPLAY INVISIBLE (-3925 3250);
FORCEPROP 2 LAST $SEC 1
J 0
(-3925 3250);
DISPLAY 0.680851 (-3925 3250);
PAINT MONO (-3925 3250);
DISPLAY INVISIBLE (-3925 3250);
FORCEPROP 2 LAST CDS_SEC 1
J 0
(-3925 3250);
DISPLAY 1.021277 (-3925 3250);
DISPLAY INVISIBLE (-3925 3250);
FORCEADD OFFPAGE..2
(-5150 3250);
FORCEPROP 2 LAST $XR1 235 
J 0
(-4841 3250);
DISPLAY 0.638298 (-4841 3250);
PAINT MONO (-4841 3250);
FORCEPROP 2 LAST $XR0 158 
J 0
(-4961 3250);
DISPLAY 0.638298 (-4961 3250);
PAINT MONO (-4961 3250);
FORCEPROP 2 LAST CDS_LIB standard
J 0
(-5150 3250);
PAINT MONO (-5150 3250);
DISPLAY INVISIBLE (-5150 3250);
FORCEPROP 1 LAST OFFPAGE TRUE
J 0
(-4825 3125);
DISPLAY 0.872340 (-4825 3125);
PAINT GREEN (-4825 3125);
DISPLAY INVISIBLE (-4825 3125);
FORCEPROP 1 LAST COMMENT_BODY TRUE
J 0
(-5195 3155);
DISPLAY 0.872340 (-5195 3155);
PAINT GREEN (-5195 3155);
DISPLAY INVISIBLE (-5195 3155);
FORCEPROP 2 LAST PATH I56
J 0
(-4800 3300);
DISPLAY 1.021277 (-4800 3300);
DISPLAY INVISIBLE (-4800 3300);
FORCEADD OFFPAGE..2
(-5150 3150);
FORCEPROP 2 LAST $XR1 235 
J 0
(-4841 3150);
DISPLAY 0.638298 (-4841 3150);
PAINT MONO (-4841 3150);
FORCEPROP 2 LAST $XR0 164 
J 0
(-4961 3150);
DISPLAY 0.638298 (-4961 3150);
PAINT MONO (-4961 3150);
FORCEPROP 2 LAST CDS_LIB standard
J 0
(-5150 3150);
PAINT MONO (-5150 3150);
DISPLAY INVISIBLE (-5150 3150);
FORCEPROP 1 LAST OFFPAGE TRUE
J 0
(-4825 3025);
DISPLAY 0.872340 (-4825 3025);
PAINT GREEN (-4825 3025);
DISPLAY INVISIBLE (-4825 3025);
FORCEPROP 1 LAST COMMENT_BODY TRUE
J 0
(-5195 3055);
DISPLAY 0.872340 (-5195 3055);
PAINT GREEN (-5195 3055);
DISPLAY INVISIBLE (-5195 3055);
FORCEPROP 2 LAST PATH I57
J 0
(-4950 3200);
DISPLAY 1.021277 (-4950 3200);
DISPLAY INVISIBLE (-4950 3200);
FORCEADD OFFPAGE..1
(-5800 3750);
FORCEPROP 2 LAST $XR1 235 
J 0
(-6172 3750);
DISPLAY 0.638298 (-6172 3750);
PAINT MONO (-6172 3750);
FORCEPROP 2 LAST $XR0 158 
J 0
(-6052 3750);
DISPLAY 0.638298 (-6052 3750);
PAINT MONO (-6052 3750);
FORCEPROP 2 LAST CDS_LIB standard
J 0
(-5800 3750);
PAINT MONO (-5800 3750);
DISPLAY INVISIBLE (-5800 3750);
FORCEPROP 1 LAST OFFPAGE TRUE
J 0
(-5475 3625);
DISPLAY 0.872340 (-5475 3625);
PAINT GREEN (-5475 3625);
DISPLAY INVISIBLE (-5475 3625);
FORCEPROP 1 LAST COMMENT_BODY TRUE
J 0
(-5675 3650);
DISPLAY 0.872340 (-5675 3650);
PAINT GREEN (-5675 3650);
DISPLAY INVISIBLE (-5675 3650);
FORCEPROP 2 LAST PATH I58
J 0
(-6075 3800);
DISPLAY 1.021277 (-6075 3800);
DISPLAY INVISIBLE (-6075 3800);
FORCEADD OFFPAGE..1
(-6600 7125);
FORCEPROP 2 LAST $XR0 14 
J 0
(-6821 7125);
DISPLAY 0.638298 (-6821 7125);
PAINT MONO (-6821 7125);
FORCEPROP 2 LAST CDS_LIB standard
J 0
(-6600 7125);
PAINT MONO (-6600 7125);
DISPLAY INVISIBLE (-6600 7125);
FORCEPROP 1 LAST OFFPAGE TRUE
J 0
(-6275 7000);
DISPLAY 0.872340 (-6275 7000);
PAINT GREEN (-6275 7000);
DISPLAY INVISIBLE (-6275 7000);
FORCEPROP 1 LAST COMMENT_BODY TRUE
J 0
(-6475 7025);
DISPLAY 0.872340 (-6475 7025);
PAINT GREEN (-6475 7025);
DISPLAY INVISIBLE (-6475 7025);
FORCEPROP 2 LAST PATH I59
J 0
(-6850 7175);
DISPLAY 1.021277 (-6850 7175);
DISPLAY INVISIBLE (-6850 7175);
FORCEADD OFFPAGE..2
(-600 2775);
FORCEPROP 2 LAST $XR0 45 
J 0
(-411 2775);
DISPLAY 0.638298 (-411 2775);
PAINT MONO (-411 2775);
FORCEPROP 2 LAST CDS_LIB standard
J 0
(-600 2775);
DISPLAY INVISIBLE (-600 2775);
FORCEPROP 1 LAST OFFPAGE TRUE
J 0
(-275 2650);
DISPLAY 0.872340 (-275 2650);
PAINT GREEN (-275 2650);
DISPLAY INVISIBLE (-275 2650);
FORCEPROP 1 LAST COMMENT_BODY TRUE
J 0
(-645 2680);
DISPLAY 0.872340 (-645 2680);
PAINT GREEN (-645 2680);
DISPLAY INVISIBLE (-645 2680);
FORCEPROP 2 LAST PATH I6
J 0
(-400 2825);
DISPLAY 1.021277 (-400 2825);
DISPLAY INVISIBLE (-400 2825);
FORCEADD OFFPAGE..3
R 2
(-6600 7025);
FORCEPROP 2 LAST $XR0 14 
J 0
(-6849 7025);
DISPLAY 0.638298 (-6849 7025);
PAINT MONO (-6849 7025);
FORCEPROP 2 LAST CDS_LIB standard
J 0
(-6600 7025);
PAINT MONO (-6600 7025);
DISPLAY INVISIBLE (-6600 7025);
FORCEPROP 1 LAST OFFPAGE TRUE
J 2
(-6925 6900);
DISPLAY 0.872340 (-6925 6900);
DISPLAY INVISIBLE (-6925 6900);
FORCEPROP 1 LAST COMMENT_BODY TRUE
J 2
(-6550 6925);
DISPLAY 0.872340 (-6550 6925);
PAINT GREEN (-6550 6925);
DISPLAY INVISIBLE (-6550 6925);
FORCEPROP 2 LAST PATH I60
J 0
(-6900 7075);
DISPLAY 1.021277 (-6900 7075);
DISPLAY INVISIBLE (-6900 7075);
FORCEADD OFFPAGE..3
R 2
(-6600 5425);
FORCEPROP 2 LAST $XR0 45 
J 0
(-6849 5425);
DISPLAY 0.638298 (-6849 5425);
PAINT MONO (-6849 5425);
FORCEPROP 2 LAST CDS_LIB standard
J 0
(-6600 5425);
PAINT MONO (-6600 5425);
DISPLAY INVISIBLE (-6600 5425);
FORCEPROP 1 LAST OFFPAGE TRUE
J 2
(-6925 5300);
DISPLAY 0.872340 (-6925 5300);
DISPLAY INVISIBLE (-6925 5300);
FORCEPROP 1 LAST COMMENT_BODY TRUE
J 2
(-6550 5325);
DISPLAY 0.872340 (-6550 5325);
PAINT GREEN (-6550 5325);
DISPLAY INVISIBLE (-6550 5325);
FORCEPROP 2 LAST PATH I61
J 0
(-6900 5475);
DISPLAY 1.021277 (-6900 5475);
DISPLAY INVISIBLE (-6900 5475);
FORCEADD OFFPAGE..1
(-6600 5525);
FORCEPROP 2 LAST $XR0 45 
J 0
(-6821 5525);
DISPLAY 0.638298 (-6821 5525);
PAINT MONO (-6821 5525);
FORCEPROP 2 LAST CDS_LIB standard
J 0
(-6600 5525);
PAINT MONO (-6600 5525);
DISPLAY INVISIBLE (-6600 5525);
FORCEPROP 1 LAST OFFPAGE TRUE
J 0
(-6275 5400);
DISPLAY 0.872340 (-6275 5400);
PAINT GREEN (-6275 5400);
DISPLAY INVISIBLE (-6275 5400);
FORCEPROP 1 LAST COMMENT_BODY TRUE
J 0
(-6475 5425);
DISPLAY 0.872340 (-6475 5425);
PAINT GREEN (-6475 5425);
DISPLAY INVISIBLE (-6475 5425);
FORCEPROP 2 LAST PATH I62
J 0
(-6850 5575);
DISPLAY 1.021277 (-6850 5575);
DISPLAY INVISIBLE (-6850 5575);
FORCEADD UNIVERSAL_GND..1
(-6425 2975);
FORCEPROP 3 LASTPIN (-6425 3025) SIG_NAME GND\g
J 0
(-6415 3035);
DISPLAY 0.659574 (-6415 3035);
PAINT MONO (-6415 3035);
DISPLAY INVISIBLE (-6415 3035);
FORCEPROP 2 LAST CDS_LIB logical_power
J 0
(-6425 2975);
PAINT MONO (-6425 2975);
DISPLAY INVISIBLE (-6425 2975);
FORCEPROP 1 LAST HDL_POWER GND
J 1
(-6400 2900);
DISPLAY 0.872340 (-6400 2900);
PAINT GREEN (-6400 2900);
DISPLAY INVISIBLE (-6400 2900);
FORCEPROP 1 LAST PATH I63
J 0
(-6350 2975);
DISPLAY 0.872340 (-6350 2975);
PAINT AQUA (-6350 2975);
DISPLAY INVISIBLE (-6350 2975);
FORCEADD CONN3_210HP1030BR1..1
R 2
(-6725 3200);
FORCEPROP 1 LAST PART_NUMBER DFHD03MS213
J 2
(-6662 3379);
DISPLAY 0.723404 (-6662 3379);
PAINT GREEN (-6662 3379);
DISPLAY INVISIBLE (-6662 3379);
FORCEPROP 2 LAST PART_TYPE THLF
J 2
(-6900 3550);
DISPLAY 0.638298 (-6900 3550);
FORCEPROP 2 LAST VALUE CONN3_210-HP1-030BR1
J 2
(-6425 3500);
DISPLAY 0.638298 (-6425 3500);
FORCEPROP 1 LAST MATERIAL IO
J 2
(-6662 3324);
DISPLAY 0.723404 (-6662 3324);
PAINT GREEN (-6662 3324);
FORCEPROP 1 LAST $LOCATION JP7
J 2
(-6662 3429);
DISPLAY 0.723404 (-6662 3429);
PAINT GREEN (-6662 3429);
FORCEPROP 2 LASTPIN (-6525 3250) $PN 1
J 0
(-6515 3260);
DISPLAY 0.808511 (-6515 3260);
FORCEPROP 2 LASTPIN (-6525 3200) $PN 2
J 0
(-6515 3210);
DISPLAY 0.808511 (-6515 3210);
FORCEPROP 2 LASTPIN (-6525 3150) $PN 3
J 0
(-6515 3160);
DISPLAY 0.808511 (-6515 3160);
FORCEPROP 2 LAST CDS_LIB pure_quanta
J 0
(-6725 3200);
PAINT MONO (-6725 3200);
DISPLAY INVISIBLE (-6725 3200);
FORCEPROP 1 LAST CDS_LMAN_SYM_OUTLINE -50,100,50,-100
J 2
(-6725 3200);
DISPLAY 0.468085 (-6725 3200);
PAINT GREEN (-6725 3200);
DISPLAY INVISIBLE (-6725 3200);
FORCEPROP 1 LAST NEEDS_NO_SIZE TRUE
J 2
(-6725 3200);
DISPLAY 0.723404 (-6725 3200);
PAINT GREEN (-6725 3200);
DISPLAY INVISIBLE (-6725 3200);
FORCEPROP 1 LAST PATH I64
J 2
(-6725 3200);
DISPLAY 0.723404 (-6725 3200);
PAINT GREEN (-6725 3200);
DISPLAY INVISIBLE (-6725 3200);
FORCEPROP 2 LAST CDS_LOCATION JP7
J 0
(-6900 3600);
DISPLAY 1.021277 (-6900 3600);
DISPLAY INVISIBLE (-6900 3600);
FORCEPROP 2 LAST $SEC 1
J 0
(-6900 3600);
DISPLAY 0.680851 (-6900 3600);
PAINT MONO (-6900 3600);
DISPLAY INVISIBLE (-6900 3600);
FORCEPROP 2 LAST CDS_SEC 1
J 0
(-6900 3600);
DISPLAY 1.021277 (-6900 3600);
DISPLAY INVISIBLE (-6900 3600);
FORCEADD UNIVERSAL_GND..1
(-1350 2200);
FORCEPROP 3 LASTPIN (-1350 2250) SIG_NAME GND\g
J 0
(-1340 2260);
DISPLAY 0.659574 (-1340 2260);
PAINT MONO (-1340 2260);
DISPLAY INVISIBLE (-1340 2260);
FORCEPROP 2 LAST CDS_LIB logical_power
J 0
(-1350 2200);
DISPLAY INVISIBLE (-1350 2200);
FORCEPROP 1 LAST HDL_POWER GND
J 1
(-1325 2125);
DISPLAY 0.872340 (-1325 2125);
PAINT GREEN (-1325 2125);
DISPLAY INVISIBLE (-1325 2125);
FORCEPROP 1 LAST PATH I65
J 0
(-1275 2200);
DISPLAY 0.872340 (-1275 2200);
PAINT AQUA (-1275 2200);
DISPLAY INVISIBLE (-1275 2200);
FORCEADD UNIVERSAL_GND..1
(-2500 2200);
FORCEPROP 3 LASTPIN (-2500 2250) SIG_NAME GND\g
J 0
(-2490 2260);
DISPLAY 0.659574 (-2490 2260);
PAINT MONO (-2490 2260);
DISPLAY INVISIBLE (-2490 2260);
FORCEPROP 2 LAST CDS_LIB logical_power
J 0
(-2500 2200);
DISPLAY INVISIBLE (-2500 2200);
FORCEPROP 1 LAST HDL_POWER GND
J 1
(-2475 2125);
DISPLAY 0.872340 (-2475 2125);
PAINT GREEN (-2475 2125);
DISPLAY INVISIBLE (-2475 2125);
FORCEPROP 1 LAST PATH I67
J 0
(-2425 2200);
DISPLAY 0.872340 (-2425 2200);
PAINT AQUA (-2425 2200);
DISPLAY INVISIBLE (-2425 2200);
FORCEADD Q_RES..1
(-5150 2450);
FORCEPROP 1 LAST PART_NUMBER CS00002JB13
J 0
(-5250 2525);
DISPLAY 0.510638 (-5250 2525);
DISPLAY INVISIBLE (-5250 2525);
FORCEPROP 1 LAST TOLERANCE 5%
J 0
(-4975 2450);
DISPLAY 0.638298 (-4975 2450);
FORCEPROP 1 LAST VALUE 0
J 2
(-5000 2450);
DISPLAY 0.638298 (-5000 2450);
FORCEPROP 1 LAST WATTAGE 1/16W
J 2
(-5025 2575);
DISPLAY 0.510638 (-5025 2575);
FORCEPROP 1 LAST MATERIAL CHIP
J 0
(-5250 2575);
DISPLAY 0.510638 (-5250 2575);
FORCEPROP 1 LAST PACK_TYPE 0402LF
J 0
(-5250 2625);
DISPLAY 0.510638 (-5250 2625);
FORCEPROP 1 LAST $LOCATION R999
J 0
(-5350 2450);
DISPLAY 0.638298 (-5350 2450);
FORCEPROP 1 LASTPIN (-5250 2450) $PN 1
J 0
(-5238 2462);
DISPLAY 0.787234 (-5238 2462);
FORCEPROP 1 LASTPIN (-5050 2450) $PN 2
J 0
(-5088 2462);
DISPLAY 0.787234 (-5088 2462);
FORCEPROP 2 LAST CDS_LIB pure_quanta
J 0
(-5150 2450);
PAINT MONO (-5150 2450);
DISPLAY INVISIBLE (-5150 2450);
FORCEPROP 1 LAST PATH I69
J 0
(-5200 2600);
DISPLAY 0.978723 (-5200 2600);
PAINT WHITE (-5200 2600);
DISPLAY INVISIBLE (-5200 2600);
FORCEPROP 2 LAST CDS_LOCATION R999
J 0
(-5200 2650);
DISPLAY 1.021277 (-5200 2650);
DISPLAY INVISIBLE (-5200 2650);
FORCEPROP 2 LAST $SEC 1
J 0
(-5200 2650);
DISPLAY 0.680851 (-5200 2650);
PAINT MONO (-5200 2650);
DISPLAY INVISIBLE (-5200 2650);
FORCEPROP 2 LAST CDS_SEC 1
J 0
(-5200 2650);
DISPLAY 1.021277 (-5200 2650);
DISPLAY INVISIBLE (-5200 2650);
FORCEADD UNIVERSAL_POWER..1
(-1350 4575);
FORCEPROP 3 LASTPIN (-1350 4525) SIG_NAME PVNN_TERM_CPU0\g
J 0
(-1340 4535);
DISPLAY 0.659574 (-1340 4535);
PAINT MONO (-1340 4535);
DISPLAY INVISIBLE (-1340 4535);
FORCEPROP 1 LAST HDL_POWER PVNN_TERM_CPU0
J 1
(-1350 4625);
DISPLAY 0.872340 (-1350 4625);
PAINT GREEN (-1350 4625);
FORCEPROP 2 LAST CDS_LIB logical_power
J 0
(-1350 4575);
DISPLAY INVISIBLE (-1350 4575);
FORCEPROP 1 LAST PATH I7
J 0
(-1300 4600);
DISPLAY 0.872340 (-1300 4600);
PAINT AQUA (-1300 4600);
DISPLAY INVISIBLE (-1300 4600);
FORCEADD OFFPAGE..1
(-6350 2450);
FORCEPROP 2 LAST $XR1 235 
J 0
(-6722 2450);
DISPLAY 0.638298 (-6722 2450);
PAINT MONO (-6722 2450);
FORCEPROP 2 LAST $XR0 164 
J 0
(-6602 2450);
DISPLAY 0.638298 (-6602 2450);
PAINT MONO (-6602 2450);
FORCEPROP 2 LAST CDS_LIB standard
J 0
(-6350 2450);
PAINT MONO (-6350 2450);
DISPLAY INVISIBLE (-6350 2450);
FORCEPROP 1 LAST OFFPAGE TRUE
J 0
(-6025 2325);
DISPLAY 0.872340 (-6025 2325);
PAINT GREEN (-6025 2325);
DISPLAY INVISIBLE (-6025 2325);
FORCEPROP 1 LAST COMMENT_BODY TRUE
J 0
(-6225 2350);
DISPLAY 0.872340 (-6225 2350);
PAINT GREEN (-6225 2350);
DISPLAY INVISIBLE (-6225 2350);
FORCEPROP 2 LAST PATH I70
J 0
(-6625 2500);
DISPLAY 1.021277 (-6625 2500);
DISPLAY INVISIBLE (-6625 2500);
FORCEADD Q_RES..1
(-2000 5525);
FORCEPROP 1 LAST PART_NUMBER CS03322FB03
J 0
(-2100 5575);
DISPLAY 0.319149 (-2100 5575);
DISPLAY INVISIBLE (-2100 5575);
FORCEPROP 1 LAST WATTAGE 1/16W
J 2
(-1900 5600);
DISPLAY 0.319149 (-1900 5600);
FORCEPROP 1 LAST PACK_TYPE 0402LF
J 0
(-2100 5600);
DISPLAY 0.319149 (-2100 5600);
FORCEPROP 1 LAST TOLERANCE 1%
J 0
(-1800 5525);
DISPLAY 0.404255 (-1800 5525);
FORCEPROP 1 LAST MATERIAL CHIP
J 0
(-1725 5525);
DISPLAY 0.404255 (-1725 5525);
FORCEPROP 1 LAST VALUE 33.2
J 2
(-1825 5525);
DISPLAY 0.404255 (-1825 5525);
FORCEPROP 1 LAST $LOCATION R2479
J 0
(-2250 5525);
DISPLAY 0.787234 (-2250 5525);
FORCEPROP 1 LASTPIN (-2100 5525) $PN 1
J 0
(-2088 5537);
DISPLAY 0.787234 (-2088 5537);
PAINT MONO (-2088 5537);
FORCEPROP 1 LASTPIN (-1900 5525) $PN 2
J 0
(-1938 5537);
DISPLAY 0.787234 (-1938 5537);
PAINT MONO (-1938 5537);
FORCEPROP 2 LAST CDS_LIB pure_quanta
J 0
(-2000 5525);
DISPLAY INVISIBLE (-2000 5525);
FORCEPROP 1 LAST PATH I76
J 0
(-2050 5675);
DISPLAY 0.978723 (-2050 5675);
PAINT WHITE (-2050 5675);
DISPLAY INVISIBLE (-2050 5675);
FORCEPROP 0 LAST CDS_LOCATION R2479
J 0
(-1900 5625);
DISPLAY 1.021277 (-1900 5625);
DISPLAY INVISIBLE (-1900 5625);
FORCEPROP 0 LAST $SEC 1
J 0
(-1900 5625);
DISPLAY 0.680851 (-1900 5625);
PAINT MONO (-1900 5625);
DISPLAY INVISIBLE (-1900 5625);
FORCEPROP 0 LAST CDS_SEC 1
J 0
(-1900 5625);
DISPLAY 1.021277 (-1900 5625);
DISPLAY INVISIBLE (-1900 5625);
FORCEADD Q_RES..1
(-2000 5425);
FORCEPROP 1 LAST PART_NUMBER CS03322FB03
J 0
(-2050 5475);
DISPLAY 0.404255 (-2050 5475);
DISPLAY INVISIBLE (-2050 5475);
FORCEPROP 1 LAST VALUE 33.2
J 2
(-1825 5425);
DISPLAY 0.404255 (-1825 5425);
FORCEPROP 1 LAST TOLERANCE 1%
J 0
(-1800 5425);
DISPLAY 0.404255 (-1800 5425);
FORCEPROP 1 LAST MATERIAL CHIP
J 0
(-1725 5425);
DISPLAY 0.404255 (-1725 5425);
FORCEPROP 1 LAST $LOCATION R2480
J 0
(-2250 5425);
DISPLAY 0.787234 (-2250 5425);
FORCEPROP 1 LASTPIN (-2100 5425) $PN 1
J 0
(-2088 5437);
DISPLAY 0.787234 (-2088 5437);
PAINT MONO (-2088 5437);
FORCEPROP 1 LASTPIN (-1900 5425) $PN 2
J 0
(-1938 5437);
DISPLAY 0.787234 (-1938 5437);
PAINT MONO (-1938 5437);
FORCEPROP 1 LAST PACK_TYPE 0402LF
J 0
(-1700 5425);
DISPLAY 0.510638 (-1700 5425);
DISPLAY INVISIBLE (-1700 5425);
FORCEPROP 1 LAST WATTAGE 1/16W
J 2
(-1825 5500);
DISPLAY 0.404255 (-1825 5500);
DISPLAY INVISIBLE (-1825 5500);
FORCEPROP 2 LAST CDS_LIB pure_quanta
J 0
(-2000 5425);
DISPLAY INVISIBLE (-2000 5425);
FORCEPROP 1 LAST PATH I77
J 0
(-2050 5575);
DISPLAY 0.978723 (-2050 5575);
PAINT WHITE (-2050 5575);
DISPLAY INVISIBLE (-2050 5575);
FORCEPROP 0 LAST CDS_LOCATION R2480
J 0
(-2250 5475);
DISPLAY 1.021277 (-2250 5475);
DISPLAY INVISIBLE (-2250 5475);
FORCEPROP 0 LAST $SEC 1
J 0
(-2250 5475);
DISPLAY 0.680851 (-2250 5475);
PAINT MONO (-2250 5475);
DISPLAY INVISIBLE (-2250 5475);
FORCEPROP 0 LAST CDS_SEC 1
J 0
(-2250 5475);
DISPLAY 1.021277 (-2250 5475);
DISPLAY INVISIBLE (-2250 5475);
FORCEADD OFFPAGE..3
(-275 5425);
FORCEPROP 2 LAST $XR0 164 
J 0
(-61 5425);
DISPLAY 0.638298 (-61 5425);
PAINT MONO (-61 5425);
FORCEPROP 2 LAST CDS_LIB standard
J 0
(-275 5425);
PAINT MONO (-275 5425);
DISPLAY INVISIBLE (-275 5425);
FORCEPROP 1 LAST OFFPAGE TRUE
J 0
(50 5300);
DISPLAY 0.872340 (50 5300);
PAINT GREEN (50 5300);
DISPLAY INVISIBLE (50 5300);
FORCEPROP 1 LAST COMMENT_BODY TRUE
J 0
(-325 5325);
DISPLAY 0.872340 (-325 5325);
PAINT GREEN (-325 5325);
DISPLAY INVISIBLE (-325 5325);
FORCEPROP 2 LAST PATH I78
J 0
(125 5475);
DISPLAY 1.021277 (125 5475);
DISPLAY INVISIBLE (125 5475);
FORCEADD OFFPAGE..2
(-275 5525);
FORCEPROP 2 LAST $XR0 164 
J 0
(-86 5525);
DISPLAY 0.638298 (-86 5525);
PAINT MONO (-86 5525);
FORCEPROP 2 LAST CDS_LIB standard
J 0
(-275 5525);
PAINT MONO (-275 5525);
DISPLAY INVISIBLE (-275 5525);
FORCEPROP 1 LAST OFFPAGE TRUE
J 0
(50 5400);
DISPLAY 0.872340 (50 5400);
PAINT GREEN (50 5400);
DISPLAY INVISIBLE (50 5400);
FORCEPROP 1 LAST COMMENT_BODY TRUE
J 0
(-320 5430);
DISPLAY 0.872340 (-320 5430);
PAINT GREEN (-320 5430);
DISPLAY INVISIBLE (-320 5430);
FORCEPROP 2 LAST PATH I79
J 0
(75 5575);
DISPLAY 1.021277 (75 5575);
DISPLAY INVISIBLE (75 5575);
FORCEADD Q_RES..2
(-1350 4325);
FORCEPROP 1 LAST PART_NUMBER CS24702JB10
J 0
(-1310 4200);
DISPLAY 0.510638 (-1310 4200);
DISPLAY INVISIBLE (-1310 4200);
FORCEPROP 1 LAST MATERIAL CHIP
J 0
(-1310 4250);
DISPLAY 0.510638 (-1310 4250);
FORCEPROP 1 LAST WATTAGE 1/16W
J 0
(-1310 4300);
DISPLAY 0.510638 (-1310 4300);
FORCEPROP 1 LAST TOLERANCE 5%
J 0
(-1305 4350);
DISPLAY 0.510638 (-1305 4350);
FORCEPROP 1 LAST VALUE 4.7K
J 0
(-1305 4400);
DISPLAY 0.510638 (-1305 4400);
FORCEPROP 1 LAST PACK_TYPE 0402LF
J 0
(-1310 4150);
DISPLAY 0.510638 (-1310 4150);
FORCEPROP 1 LAST $LOCATION R1006
J 0
(-1305 4450);
DISPLAY 0.787234 (-1305 4450);
FORCEPROP 1 LASTPIN (-1350 4425) $PN 1
J 0
(-1345 4387);
DISPLAY 0.787234 (-1345 4387);
FORCEPROP 1 LASTPIN (-1350 4225) $PN 2
J 0
(-1345 4235);
DISPLAY 0.787234 (-1345 4235);
FORCEPROP 2 LAST CDS_LIB pure_quanta
J 0
(-1350 4325);
PAINT MONO (-1350 4325);
DISPLAY INVISIBLE (-1350 4325);
FORCEPROP 1 LAST PATH I8
J 0
(-1300 4500);
DISPLAY 0.978723 (-1300 4500);
PAINT WHITE (-1300 4500);
DISPLAY INVISIBLE (-1300 4500);
FORCEPROP 2 LAST CDS_LOCATION R1006
J 0
(-1300 4550);
DISPLAY 1.021277 (-1300 4550);
DISPLAY INVISIBLE (-1300 4550);
FORCEPROP 2 LAST $SEC 1
J 0
(-1300 4550);
DISPLAY 0.680851 (-1300 4550);
PAINT MONO (-1300 4550);
DISPLAY INVISIBLE (-1300 4550);
FORCEPROP 2 LAST CDS_SEC 1
J 0
(-1300 4550);
DISPLAY 1.021277 (-1300 4550);
DISPLAY INVISIBLE (-1300 4550);
FORCEADD UNIVERSAL_POWER..1
(-750 6325);
FORCEPROP 3 LASTPIN (-750 6275) SIG_NAME P3V3_AUX\g
J 0
(-740 6285);
DISPLAY 0.659574 (-740 6285);
PAINT MONO (-740 6285);
DISPLAY INVISIBLE (-740 6285);
FORCEPROP 1 LAST HDL_POWER P3V3_AUX
J 1
(-750 6375);
DISPLAY 0.872340 (-750 6375);
PAINT GREEN (-750 6375);
FORCEPROP 2 LAST CDS_LIB logical_power
J 0
(-750 6325);
PAINT MONO (-750 6325);
DISPLAY INVISIBLE (-750 6325);
FORCEPROP 1 LAST PATH I80
J 0
(-700 6350);
DISPLAY 0.872340 (-700 6350);
PAINT AQUA (-700 6350);
DISPLAY INVISIBLE (-700 6350);
FORCEADD Q_RES..2
(-550 5975);
FORCEPROP 1 LAST PART_NUMBER CS21002FB06
J 0
(-510 5800);
DISPLAY 0.510638 (-510 5800);
DISPLAY INVISIBLE (-510 5800);
FORCEPROP 1 LAST VALUE 1K
J 0
(-505 6050);
DISPLAY 0.510638 (-505 6050);
FORCEPROP 1 LAST MATERIAL CHIP
J 0
(-510 5900);
DISPLAY 0.510638 (-510 5900);
FORCEPROP 1 LAST PACK_TYPE 0402LF
J 0
(-510 5850);
DISPLAY 0.510638 (-510 5850);
FORCEPROP 1 LAST WATTAGE 1/16W
J 0
(-510 5950);
DISPLAY 0.510638 (-510 5950);
FORCEPROP 1 LAST TOLERANCE 1%
J 0
(-505 6000);
DISPLAY 0.510638 (-505 6000);
FORCEPROP 1 LAST $LOCATION R968
J 0
(-505 6100);
DISPLAY 0.978723 (-505 6100);
FORCEPROP 1 LASTPIN (-550 6075) $PN 1
J 0
(-545 6037);
DISPLAY 0.787234 (-545 6037);
FORCEPROP 1 LASTPIN (-550 5875) $PN 2
J 0
(-545 5885);
DISPLAY 0.787234 (-545 5885);
FORCEPROP 2 LAST CDS_LIB pure_quanta
J 0
(-550 5975);
PAINT MONO (-550 5975);
DISPLAY INVISIBLE (-550 5975);
FORCEPROP 1 LAST PATH I81
J 0
(-500 6150);
DISPLAY 0.978723 (-500 6150);
PAINT WHITE (-500 6150);
DISPLAY INVISIBLE (-500 6150);
FORCEPROP 2 LAST CDS_LOCATION R968
J 0
(-500 6200);
DISPLAY 1.021277 (-500 6200);
DISPLAY INVISIBLE (-500 6200);
FORCEPROP 2 LAST $SEC 1
J 0
(-500 6200);
DISPLAY 0.680851 (-500 6200);
PAINT MONO (-500 6200);
DISPLAY INVISIBLE (-500 6200);
FORCEPROP 2 LAST CDS_SEC 1
J 0
(-500 6200);
DISPLAY 1.021277 (-500 6200);
DISPLAY INVISIBLE (-500 6200);
FORCEADD Q_RES..2
(-750 5975);
FORCEPROP 1 LAST PART_NUMBER CS21002FB06
J 0
(-710 5800);
DISPLAY 0.638298 (-710 5800);
DISPLAY INVISIBLE (-710 5800);
FORCEPROP 1 LAST TOLERANCE 1%
J 0
(-705 6000);
DISPLAY 0.510638 (-705 6000);
FORCEPROP 1 LAST VALUE 1K
J 0
(-705 6050);
DISPLAY 0.510638 (-705 6050);
FORCEPROP 1 LAST MATERIAL CHIP
J 0
(-710 5900);
DISPLAY 0.510638 (-710 5900);
FORCEPROP 1 LAST WATTAGE 1/16W
J 0
(-710 5950);
DISPLAY 0.510638 (-710 5950);
FORCEPROP 1 LAST PACK_TYPE 0402LF
J 0
(-710 5850);
DISPLAY 0.510638 (-710 5850);
FORCEPROP 1 LAST $LOCATION R966
J 0
(-705 6100);
DISPLAY 0.978723 (-705 6100);
FORCEPROP 1 LASTPIN (-750 6075) $PN 1
J 0
(-745 6037);
DISPLAY 0.787234 (-745 6037);
FORCEPROP 1 LASTPIN (-750 5875) $PN 2
J 0
(-745 5885);
DISPLAY 0.787234 (-745 5885);
FORCEPROP 2 LAST CDS_LIB pure_quanta
J 0
(-750 5975);
PAINT MONO (-750 5975);
DISPLAY INVISIBLE (-750 5975);
FORCEPROP 1 LAST PATH I82
J 0
(-700 6150);
DISPLAY 0.978723 (-700 6150);
PAINT WHITE (-700 6150);
DISPLAY INVISIBLE (-700 6150);
FORCEPROP 2 LAST CDS_LOCATION R966
J 0
(-700 6200);
DISPLAY 1.021277 (-700 6200);
DISPLAY INVISIBLE (-700 6200);
FORCEPROP 2 LAST $SEC 1
J 0
(-700 6200);
DISPLAY 0.680851 (-700 6200);
PAINT MONO (-700 6200);
DISPLAY INVISIBLE (-700 6200);
FORCEPROP 2 LAST CDS_SEC 1
J 0
(-700 6200);
DISPLAY 1.021277 (-700 6200);
DISPLAY INVISIBLE (-700 6200);
FORCEADD Q_RES..1
(-2000 7125);
FORCEPROP 1 LAST PART_NUMBER CS03322FB03
J 0
(-2100 7175);
DISPLAY 0.319149 (-2100 7175);
DISPLAY INVISIBLE (-2100 7175);
FORCEPROP 1 LAST VALUE 33.2
J 2
(-1825 7125);
DISPLAY 0.404255 (-1825 7125);
FORCEPROP 1 LAST MATERIAL CHIP
J 0
(-1725 7125);
DISPLAY 0.404255 (-1725 7125);
FORCEPROP 1 LAST TOLERANCE 1%
J 0
(-1800 7125);
DISPLAY 0.404255 (-1800 7125);
FORCEPROP 1 LAST PACK_TYPE 0402LF
J 0
(-2100 7200);
DISPLAY 0.319149 (-2100 7200);
FORCEPROP 1 LAST WATTAGE 1/16W
J 2
(-1900 7200);
DISPLAY 0.319149 (-1900 7200);
FORCEPROP 1 LAST $LOCATION R2477
J 0
(-2250 7125);
DISPLAY 0.787234 (-2250 7125);
FORCEPROP 1 LASTPIN (-2100 7125) $PN 1
J 0
(-2088 7137);
DISPLAY 0.787234 (-2088 7137);
PAINT MONO (-2088 7137);
FORCEPROP 1 LASTPIN (-1900 7125) $PN 2
J 0
(-1938 7137);
DISPLAY 0.787234 (-1938 7137);
PAINT MONO (-1938 7137);
FORCEPROP 2 LAST CDS_LIB pure_quanta
J 0
(-2000 7125);
DISPLAY INVISIBLE (-2000 7125);
FORCEPROP 1 LAST PATH I88
J 0
(-2050 7275);
DISPLAY 0.978723 (-2050 7275);
PAINT WHITE (-2050 7275);
DISPLAY INVISIBLE (-2050 7275);
FORCEPROP 0 LAST CDS_LOCATION R2477
J 0
(-1900 7225);
DISPLAY 1.021277 (-1900 7225);
DISPLAY INVISIBLE (-1900 7225);
FORCEPROP 0 LAST $SEC 1
J 0
(-1900 7225);
DISPLAY 0.680851 (-1900 7225);
PAINT MONO (-1900 7225);
DISPLAY INVISIBLE (-1900 7225);
FORCEPROP 0 LAST CDS_SEC 1
J 0
(-1900 7225);
DISPLAY 1.021277 (-1900 7225);
DISPLAY INVISIBLE (-1900 7225);
FORCEADD Q_RES..1
(-2000 7025);
FORCEPROP 1 LAST PART_NUMBER CS03322FB03
J 0
(-2050 7075);
DISPLAY 0.404255 (-2050 7075);
DISPLAY INVISIBLE (-2050 7075);
FORCEPROP 1 LAST MATERIAL CHIP
J 0
(-1725 7025);
DISPLAY 0.404255 (-1725 7025);
FORCEPROP 1 LAST TOLERANCE 1%
J 0
(-1800 7025);
DISPLAY 0.404255 (-1800 7025);
FORCEPROP 1 LAST VALUE 33.2
J 2
(-1825 7025);
DISPLAY 0.404255 (-1825 7025);
FORCEPROP 1 LAST $LOCATION R2478
J 0
(-2250 7025);
DISPLAY 0.787234 (-2250 7025);
FORCEPROP 1 LASTPIN (-2100 7025) $PN 1
J 0
(-2088 7037);
DISPLAY 0.787234 (-2088 7037);
PAINT MONO (-2088 7037);
FORCEPROP 1 LASTPIN (-1900 7025) $PN 2
J 0
(-1938 7037);
DISPLAY 0.787234 (-1938 7037);
PAINT MONO (-1938 7037);
FORCEPROP 2 LAST CDS_LIB pure_quanta
J 0
(-2000 7025);
DISPLAY INVISIBLE (-2000 7025);
FORCEPROP 1 LAST WATTAGE 1/16W
J 2
(-1825 7100);
DISPLAY 0.404255 (-1825 7100);
DISPLAY INVISIBLE (-1825 7100);
FORCEPROP 1 LAST PACK_TYPE 0402LF
J 0
(-1700 7025);
DISPLAY 0.510638 (-1700 7025);
DISPLAY INVISIBLE (-1700 7025);
FORCEPROP 1 LAST PATH I89
J 0
(-2050 7175);
DISPLAY 0.978723 (-2050 7175);
PAINT WHITE (-2050 7175);
DISPLAY INVISIBLE (-2050 7175);
FORCEPROP 0 LAST CDS_LOCATION R2478
J 0
(-2250 7075);
DISPLAY 1.021277 (-2250 7075);
DISPLAY INVISIBLE (-2250 7075);
FORCEPROP 0 LAST $SEC 1
J 0
(-2250 7075);
DISPLAY 0.680851 (-2250 7075);
PAINT MONO (-2250 7075);
DISPLAY INVISIBLE (-2250 7075);
FORCEPROP 0 LAST CDS_SEC 1
J 0
(-2250 7075);
DISPLAY 1.021277 (-2250 7075);
DISPLAY INVISIBLE (-2250 7075);
FORCEADD OFFPAGE..3
(-275 7025);
FORCEPROP 2 LAST $XR0 158 
J 0
(-61 7025);
DISPLAY 0.638298 (-61 7025);
PAINT MONO (-61 7025);
FORCEPROP 2 LAST CDS_LIB standard
J 0
(-275 7025);
PAINT MONO (-275 7025);
DISPLAY INVISIBLE (-275 7025);
FORCEPROP 1 LAST OFFPAGE TRUE
J 0
(50 6900);
DISPLAY 0.872340 (50 6900);
PAINT GREEN (50 6900);
DISPLAY INVISIBLE (50 6900);
FORCEPROP 1 LAST COMMENT_BODY TRUE
J 0
(-325 6925);
DISPLAY 0.872340 (-325 6925);
PAINT GREEN (-325 6925);
DISPLAY INVISIBLE (-325 6925);
FORCEPROP 2 LAST PATH I90
J 0
(850 7075);
DISPLAY 1.021277 (850 7075);
DISPLAY INVISIBLE (850 7075);
FORCEADD OFFPAGE..2
(-275 7125);
FORCEPROP 2 LAST $XR0 158 
J 0
(-86 7125);
DISPLAY 0.638298 (-86 7125);
PAINT MONO (-86 7125);
FORCEPROP 2 LAST CDS_LIB standard
J 0
(-275 7125);
PAINT MONO (-275 7125);
DISPLAY INVISIBLE (-275 7125);
FORCEPROP 1 LAST OFFPAGE TRUE
J 0
(50 7000);
DISPLAY 0.872340 (50 7000);
PAINT GREEN (50 7000);
DISPLAY INVISIBLE (50 7000);
FORCEPROP 1 LAST COMMENT_BODY TRUE
J 0
(-320 7030);
DISPLAY 0.872340 (-320 7030);
PAINT GREEN (-320 7030);
DISPLAY INVISIBLE (-320 7030);
FORCEPROP 2 LAST PATH I91
J 0
(675 7175);
DISPLAY 1.021277 (675 7175);
DISPLAY INVISIBLE (675 7175);
FORCEADD UNIVERSAL_POWER..1
(-750 7925);
FORCEPROP 3 LASTPIN (-750 7875) SIG_NAME P3V3_AUX\g
J 0
(-740 7885);
DISPLAY 0.659574 (-740 7885);
PAINT MONO (-740 7885);
DISPLAY INVISIBLE (-740 7885);
FORCEPROP 1 LAST HDL_POWER P3V3_AUX
J 1
(-750 7975);
DISPLAY 0.872340 (-750 7975);
PAINT GREEN (-750 7975);
FORCEPROP 2 LAST CDS_LIB logical_power
J 0
(-750 7925);
PAINT MONO (-750 7925);
DISPLAY INVISIBLE (-750 7925);
FORCEPROP 1 LAST PATH I92
J 0
(-700 7950);
DISPLAY 0.872340 (-700 7950);
PAINT AQUA (-700 7950);
DISPLAY INVISIBLE (-700 7950);
FORCEADD Q_RES..2
(-750 7575);
FORCEPROP 1 LAST PART_NUMBER CS21002FB06
J 0
(-710 7400);
DISPLAY 0.638298 (-710 7400);
DISPLAY INVISIBLE (-710 7400);
FORCEPROP 1 LAST WATTAGE 1/16W
J 0
(-710 7550);
DISPLAY 0.510638 (-710 7550);
FORCEPROP 1 LAST PACK_TYPE 0402LF
J 0
(-710 7450);
DISPLAY 0.510638 (-710 7450);
FORCEPROP 1 LAST MATERIAL CHIP
J 0
(-710 7500);
DISPLAY 0.510638 (-710 7500);
FORCEPROP 1 LAST VALUE 1K
J 0
(-705 7650);
DISPLAY 0.510638 (-705 7650);
FORCEPROP 1 LAST TOLERANCE 1%
J 0
(-705 7600);
DISPLAY 0.510638 (-705 7600);
FORCEPROP 1 LAST $LOCATION R965
J 0
(-705 7700);
DISPLAY 0.978723 (-705 7700);
FORCEPROP 1 LASTPIN (-750 7675) $PN 1
J 0
(-745 7637);
DISPLAY 0.787234 (-745 7637);
FORCEPROP 1 LASTPIN (-750 7475) $PN 2
J 0
(-745 7485);
DISPLAY 0.787234 (-745 7485);
FORCEPROP 2 LAST CDS_LIB pure_quanta
J 0
(-750 7575);
PAINT MONO (-750 7575);
DISPLAY INVISIBLE (-750 7575);
FORCEPROP 1 LAST PATH I93
J 0
(-700 7750);
DISPLAY 0.978723 (-700 7750);
PAINT WHITE (-700 7750);
DISPLAY INVISIBLE (-700 7750);
FORCEPROP 2 LAST CDS_LOCATION R965
J 0
(-700 7800);
DISPLAY 1.021277 (-700 7800);
DISPLAY INVISIBLE (-700 7800);
FORCEPROP 2 LAST $SEC 1
J 0
(-700 7800);
DISPLAY 0.680851 (-700 7800);
PAINT MONO (-700 7800);
DISPLAY INVISIBLE (-700 7800);
FORCEPROP 2 LAST CDS_SEC 1
J 0
(-700 7800);
DISPLAY 1.021277 (-700 7800);
DISPLAY INVISIBLE (-700 7800);
FORCEADD Q_RES..2
(-550 7575);
FORCEPROP 1 LAST PART_NUMBER CS21002FB06
J 0
(-510 7400);
DISPLAY 0.510638 (-510 7400);
DISPLAY INVISIBLE (-510 7400);
FORCEPROP 1 LAST PACK_TYPE 0402LF
J 0
(-510 7450);
DISPLAY 0.510638 (-510 7450);
FORCEPROP 1 LAST MATERIAL CHIP
J 0
(-510 7500);
DISPLAY 0.510638 (-510 7500);
FORCEPROP 1 LAST WATTAGE 1/16W
J 0
(-510 7550);
DISPLAY 0.510638 (-510 7550);
FORCEPROP 1 LAST TOLERANCE 1%
J 0
(-505 7600);
DISPLAY 0.510638 (-505 7600);
FORCEPROP 1 LAST VALUE 1K
J 0
(-505 7650);
DISPLAY 0.510638 (-505 7650);
FORCEPROP 1 LAST $LOCATION R967
J 0
(-505 7700);
DISPLAY 0.978723 (-505 7700);
FORCEPROP 1 LASTPIN (-550 7675) $PN 1
J 0
(-545 7637);
DISPLAY 0.787234 (-545 7637);
FORCEPROP 1 LASTPIN (-550 7475) $PN 2
J 0
(-545 7485);
DISPLAY 0.787234 (-545 7485);
FORCEPROP 2 LAST CDS_LIB pure_quanta
J 0
(-550 7575);
PAINT MONO (-550 7575);
DISPLAY INVISIBLE (-550 7575);
FORCEPROP 1 LAST PATH I94
J 0
(-500 7750);
DISPLAY 0.978723 (-500 7750);
PAINT WHITE (-500 7750);
DISPLAY INVISIBLE (-500 7750);
FORCEPROP 2 LAST CDS_LOCATION R967
J 0
(-500 7800);
DISPLAY 1.021277 (-500 7800);
DISPLAY INVISIBLE (-500 7800);
FORCEPROP 2 LAST $SEC 1
J 0
(-500 7800);
DISPLAY 0.680851 (-500 7800);
PAINT MONO (-500 7800);
DISPLAY INVISIBLE (-500 7800);
FORCEPROP 2 LAST CDS_SEC 1
J 0
(-500 7800);
DISPLAY 1.021277 (-500 7800);
DISPLAY INVISIBLE (-500 7800);
FORCEADD Q_RES..1
(-5600 5525);
FORCEPROP 1 LAST PART_NUMBER CS03322FB03
J 0
(-5725 5575);
DISPLAY 0.404255 (-5725 5575);
DISPLAY INVISIBLE (-5725 5575);
FORCEPROP 1 LAST MATERIAL CHIP
J 0
(-5300 5525);
DISPLAY 0.510638 (-5300 5525);
FORCEPROP 1 LAST TOLERANCE 1%
J 0
(-5375 5525);
DISPLAY 0.510638 (-5375 5525);
FORCEPROP 1 LAST VALUE 33.2
J 2
(-5400 5525);
DISPLAY 0.510638 (-5400 5525);
FORCEPROP 1 LAST LOCATION R961
J 0
(-5800 5525);
DISPLAY 0.638298 (-5800 5525);
FORCEPROP 1 LASTPIN (-5700 5525) $PN 1
J 0
(-5688 5537);
DISPLAY 0.787234 (-5688 5537);
PAINT MONO (-5688 5537);
FORCEPROP 1 LASTPIN (-5500 5525) $PN 2
J 0
(-5538 5537);
DISPLAY 0.787234 (-5538 5537);
PAINT MONO (-5538 5537);
FORCEPROP 1 LAST PACK_TYPE 0402LF
J 0
(-5725 5625);
DISPLAY 0.404255 (-5725 5625);
DISPLAY INVISIBLE (-5725 5625);
FORCEPROP 1 LAST WATTAGE 1/16W
J 2
(-5500 5625);
DISPLAY 0.404255 (-5500 5625);
DISPLAY INVISIBLE (-5500 5625);
FORCEPROP 2 LAST CDS_LIB pure_quanta
J 0
(-5600 5525);
DISPLAY INVISIBLE (-5600 5525);
FORCEPROP 1 LAST PATH I99
J 0
(-5650 5675);
DISPLAY 0.978723 (-5650 5675);
PAINT WHITE (-5650 5675);
DISPLAY INVISIBLE (-5650 5675);
FORCEPROP 0 LAST $SEC 1
J 0
(-5800 5575);
DISPLAY 0.680851 (-5800 5575);
PAINT MONO (-5800 5575);
DISPLAY INVISIBLE (-5800 5575);
FORCEPROP 0 LAST CDS_SEC 1
J 0
(-5800 5575);
DISPLAY 1.021277 (-5800 5575);
DISPLAY INVISIBLE (-5800 5575);
FORCEADD DESIGN_NOTE..1
(-6550 4475);
FORCEPROP 0 LAST S1 JP7: CPU PCIE ALERT
J 0
(-6750 4325);
DISPLAY 1.021277 (-6750 4325);
PAINT WHITE (-6750 4325);
FORCEPROP 2 LAST CDS_LIB logical_power
J 0
(-6550 4475);
PAINT MONO (-6550 4475);
DISPLAY INVISIBLE (-6550 4475);
FORCEPROP 1 LAST COMMENT_BODY TRUE
J 0
(-6525 4575);
DISPLAY 0.978723 (-6525 4575);
DISPLAY INVISIBLE (-6525 4575);
FORCEADD QUANTA_TITLE_BLOCK_C..1
(1175 1675);
FORCEPROP 0 LAST CDS_CON_LAST_MODIFIED Fri Aug 25 14:03:59 2023
J 0
(-710 1690);
PAINT MONO (-710 1690);
DISPLAY INVISIBLE (-710 1690);
FORCEPROP 2 LAST CUSTOM_TXT_CDS <XR_PAGE_TITLE>
J 0
(-6715 6925);
DISPLAY 0.638298 (-6715 6925);
PAINT PINK (-6715 6925);
DISPLAY INVISIBLE (-6715 6925);
FORCEPROP 2 LAST CUSTOM_TXT_CDS <CON_LAST_MODIFIED>
J 0
(-710 1690);
DISPLAY 0.978723 (-710 1690);
FORCEPROP 2 LAST CUSTOM_TXT_CDS <NAME_2>
J 0
(-2000 1725);
FORCEPROP 2 LAST CUSTOM_TXT_CDS <NAME_1>
J 0
(-2000 1850);
FORCEPROP 2 LAST CUSTOM_TXT_CDS <Q_NUMBER>
J 0
(-228 1778);
DISPLAY 1.212766 (-228 1778);
FORCEPROP 2 LAST CUSTOM_TXT_CDS <Q_PROJ>
J 0
(-1207 1777);
DISPLAY 1.212766 (-1207 1777);
FORCEPROP 2 LAST CUSTOM_TXT_CDS <Q_REV>
J 0
(991 1778);
DISPLAY 1.212766 (991 1778);
FORCEPROP 2 LAST CUSTOM_TXT_CDS <CON_PAGE_NUM> OF <CON_TOTAL_PAGES>
J 0
(729 1693);
DISPLAY 0.978723 (729 1693);
FORCEPROP 1 LAST Q_TITLE SMBUS - CPU0 &1 PEHP SMBUS
J 0
(-8091 1701);
DISPLAY 2.446809 (-8091 1701);
PAINT GREEN (-8091 1701);
FORCEPROP 1 LAST Q_DEPT 
J 1
(-2588 1724);
DISPLAY 1.957447 (-2588 1724);
PAINT GREEN (-2588 1724);
FORCEPROP 2 LAST CDS_XR_PAGE_TITLE CR-235 : @S9S_MB_2U_LIB.S9S_MB_2U(SCH_1):PAGE235
J 0
(-6715 6925);
DISPLAY 0.638298 (-6715 6925);
PAINT PINK (-6715 6925);
DISPLAY INVISIBLE (-6715 6925);
FORCEPROP 2 LAST CDS_LIB pure_quanta
J 0
(1175 1675);
PAINT MONO (1175 1675);
DISPLAY INVISIBLE (1175 1675);
FORCEPROP 1 LAST CDS_LMAN_SYM_OUTLINE -9475,6775,100,-125
J 0
(1175 1675);
DISPLAY 0.468085 (1175 1675);
PAINT GREEN (1175 1675);
DISPLAY INVISIBLE (1175 1675);
FORCEPROP 1 LAST COMMENT_BODY TRUE
J 0
(1187 1662);
DISPLAY 0.978723 (1187 1662);
PAINT GREEN (1187 1662);
DISPLAY INVISIBLE (1187 1662);
FORCEPROP 2 LAST PAGE_BORDER TRUE
J 0
(-6715 6925);
DISPLAY 0.638298 (-6715 6925);
PAINT PINK (-6715 6925);
DISPLAY INVISIBLE (-6715 6925);
WIRE 16 -1 (-1350 4525)(-1350 4425);
WIRE 16 -1 (-2500 3225)(-2500 3125);
WIRE 16 -1 (-2500 4525)(-2500 4425);
WIRE 16 -1 (-1350 3225)(-1350 3125);
WIRE 16 -1 (-5125 6275)(-5125 6125);
WIRE 16 -1 (-4350 6275)(-4350 6200);
WIRE 16 -1 (-3000 6275)(-3000 6200);
WIRE 16 -1 (-750 7875)(-750 7800);
WIRE 16 -1 (-750 6275)(-750 6200);
WIRE 16 -1 (-3975 3225)(-3975 3125);
WIRE 16 -1 (-3975 4525)(-3975 4425);
WIRE 16 -1 (-5125 7875)(-5125 7725);
WIRE 16 -1 (-4350 7875)(-4350 7800);
WIRE 16 -1 (-3000 7875)(-3000 7800);
WIRE 16 -1 (-2500 2300)(-2500 2250);
WIRE 16 -1 (-1350 2250)(-1350 2300);
WIRE 16 -1 (-6425 3200)(-6425 3025);
WIRE 16 -1 (-6525 3200)(-6425 3200);
WIRE 16 -1 (-4200 5100)(-4200 5275);
WIRE 16 -1 (-4350 5900)(-4350 5825);
WIRE 16 -1 (-4200 6700)(-4200 6875);
WIRE 16 -1 (-2500 3600)(-2500 3550);
WIRE 16 -1 (-3000 5900)(-3000 5825);
WIRE 16 -1 (-4350 7500)(-4350 7425);
WIRE 16 -1 (-3000 7500)(-3000 7425);
WIRE 16 -1 (-1350 3550)(-1350 3600);
WIRE 16 -1 (-5050 2450)(-3975 2450);
FORCEPROP 0 LAST CDS_PHYS_NET_NAME FM_SMB_PEHPCPU1_PCIE_ALERT_R_N
J 0
(-5025 2492);
PAINT MONO (-5025 2492);
DISPLAY INVISIBLE (-5025 2492);
FORCEPROP 0 LAST SIG_NAME FM_SMB_PEHPCPU1_PCIE_ALERT_R_N
J 0
(-4860 2460);
DISPLAY 0.553191 (-4860 2460);
PAINT WHITE (-4860 2460);
WIRE 16 -1 (-2750 2450)(-3975 2450);
WIRE 16 -1 (-3975 2925)(-3975 2450);
WIRE 16 -1 (-2500 2700)(-2500 2775);
WIRE 16 -1 (-2500 2925)(-2500 2775);
WIRE 16 -1 (-1700 2775)(-2500 2775);
FORCEPROP 2 LAST SIG_NAME FM_SMB_CPU1_ALERT_R1
J 0
(-2410 2785);
DISPLAY 0.553191 (-2410 2785);
PAINT WHITE (-2410 2785);
WIRE 16 -1 (-1700 2775)(-1700 2450);
WIRE 16 -1 (-1700 2450)(-1600 2450);
WIRE 16 -1 (-1350 2700)(-1350 2775);
WIRE 16 -1 (-650 2775)(-1350 2775);
FORCEPROP 2 LAST SIG_NAME FM_PEHPCPU1_ALERT_N
J 0
(-1225 2785);
DISPLAY 0.553191 (-1225 2785);
PAINT WHITE (-1225 2785);
WIRE 16 -1 (-1350 2925)(-1350 2775);
WIRE 16 -1 (-2500 4000)(-2500 4075);
WIRE 16 -1 (-2500 4225)(-2500 4075);
WIRE 16 -1 (-1700 4075)(-2500 4075);
FORCEPROP 2 LAST SIG_NAME FM_SMB_CPU0_ALERT_R1
J 0
(-2410 4085);
DISPLAY 0.553191 (-2410 4085);
PAINT WHITE (-2410 4085);
WIRE 16 -1 (-1700 4075)(-1700 3750);
WIRE 16 -1 (-1700 3750)(-1600 3750);
WIRE 16 -1 (-650 4075)(-1350 4075);
FORCEPROP 2 LAST SIG_NAME FM_PEHPCPU0_ALERT_N
J 0
(-1225 4085);
DISPLAY 0.553191 (-1225 4085);
PAINT WHITE (-1225 4085);
WIRE 16 -1 (-1350 4225)(-1350 4075);
WIRE 16 -1 (-1350 4000)(-1350 4075);
WIRE 16 -1 (-4225 3750)(-3975 3750);
FORCEPROP 0 LAST CDS_PHYS_NET_NAME FM_SMB_PEHPCPU0_PCIE_ALERT_R_N
J 0
(-4000 3792);
PAINT MONO (-4000 3792);
DISPLAY INVISIBLE (-4000 3792);
WIRE 16 -1 (-3975 4225)(-3975 3750);
WIRE 16 -1 (-2750 3750)(-3975 3750);
FORCEPROP 0 LAST SIG_NAME FM_SMB_PEHPCPU0_PCIE_ALERT_R_N
J 0
(-3900 3760);
DISPLAY 0.680851 (-3900 3760);
PAINT WHITE (-3900 3760);
WIRE 16 -1 (-5750 3750)(-4425 3750);
FORCEPROP 0 LAST CDS_PHYS_NET_NAME FM_SMB_PEHPCPU0_PCIE_ALERT_N
J 0
(-5725 3792);
PAINT MONO (-5725 3792);
DISPLAY INVISIBLE (-5725 3792);
FORCEPROP 0 LAST SIG_NAME FM_SMB_PEHPCPU0_PCIE_ALERT_N
J 0
(-5625 3760);
DISPLAY 0.680851 (-5625 3760);
PAINT WHITE (-5625 3760);
WIRE 16 2175 (-5850 6975)(-5175 6975);
WIRE 16 2175 (-5175 7200)(-5175 6975);
WIRE 16 2175 (-5850 7200)(-5850 6975);
WIRE 16 2175 (-5850 7200)(-5175 7200);
WIRE 16 -1 (-6550 7125)(-5700 7125);
FORCEPROP 0 LAST CDS_PHYS_NET_NAME SMB_PEHPCPU0_GTL_SCL
J 0
(-6510 7173);
PAINT MONO (-6510 7173);
DISPLAY INVISIBLE (-6510 7173);
FORCEPROP 2 LAST SIG_NAME SMB_PEHPCPU0_GTL_SCL
J 0
(-6435 7135);
DISPLAY 0.510638 (-6435 7135);
PAINT WHITE (-6435 7135);
WIRE 16 -1 (-5125 7325)(-5125 7125);
WIRE 16 -1 (-5125 7125)(-4100 7125);
FORCEPROP 2 LAST SIG_NAME SMB_PEHPCPU0_GTL_R_SCL
J 0
(-4810 7135);
DISPLAY 0.510638 (-4810 7135);
PAINT WHITE (-4810 7135);
WIRE 16 -1 (-5500 7125)(-5125 7125);
FORCEPROP 0 LAST CDS_PHYS_NET_NAME SMB_PEHPCPU0_GTL_R_SCL
J 0
(-5460 7173);
PAINT MONO (-5460 7173);
DISPLAY INVISIBLE (-5460 7173);
WIRE 16 -1 (-6550 7025)(-5700 7025);
FORCEPROP 0 LAST CDS_PHYS_NET_NAME SMB_PEHPCPU0_GTL_SDA
J 0
(-6510 7073);
PAINT MONO (-6510 7073);
DISPLAY INVISIBLE (-6510 7073);
FORCEPROP 2 LAST SIG_NAME SMB_PEHPCPU0_GTL_SDA
J 0
(-6435 7035);
DISPLAY 0.510638 (-6435 7035);
PAINT WHITE (-6435 7035);
WIRE 16 -1 (-4925 7025)(-4100 7025);
FORCEPROP 2 LAST SIG_NAME SMB_PEHPCPU0_GTL_R_SDA
J 0
(-4810 7035);
DISPLAY 0.510638 (-4810 7035);
PAINT WHITE (-4810 7035);
WIRE 16 -1 (-4925 7325)(-4925 7025);
WIRE 16 -1 (-5500 7025)(-4925 7025);
FORCEPROP 0 LAST CDS_PHYS_NET_NAME SMB_PEHPCPU0_GTL_R_SDA
J 0
(-5460 7073);
PAINT MONO (-5460 7073);
DISPLAY INVISIBLE (-5460 7073);
WIRE 16 2175 (-5850 5600)(-5175 5600);
WIRE 16 2175 (-5175 5600)(-5175 5375);
WIRE 16 2175 (-5850 5600)(-5850 5375);
WIRE 16 2175 (-5850 5375)(-5175 5375);
WIRE 16 -1 (-5125 6125)(-5125 5925);
WIRE 16 -1 (-4900 6125)(-5125 6125);
WIRE 16 -1 (-4900 5925)(-4900 6125);
WIRE 16 -1 (-5500 5525)(-5125 5525);
FORCEPROP 0 LAST CDS_PHYS_NET_NAME SMB_PEHPCPU1_GTL_R_SCL
J 0
(-5460 5573);
PAINT MONO (-5460 5573);
DISPLAY INVISIBLE (-5460 5573);
WIRE 16 -1 (-5125 5525)(-4100 5525);
FORCEPROP 2 LAST SIG_NAME SMB_PEHPCPU1_GTL_R_SCL
J 0
(-4810 5535);
DISPLAY 0.510638 (-4810 5535);
PAINT WHITE (-4810 5535);
WIRE 16 -1 (-5125 5725)(-5125 5525);
WIRE 16 -1 (-5500 5425)(-4900 5425);
FORCEPROP 0 LAST CDS_PHYS_NET_NAME SMB_PEHPCPU1_GTL_R_SDA
J 0
(-5460 5473);
PAINT MONO (-5460 5473);
DISPLAY INVISIBLE (-5460 5473);
WIRE 16 -1 (-4900 5425)(-4100 5425);
FORCEPROP 2 LAST SIG_NAME SMB_PEHPCPU1_GTL_R_SDA
J 0
(-4810 5435);
DISPLAY 0.510638 (-4810 5435);
PAINT WHITE (-4810 5435);
WIRE 16 -1 (-4900 5725)(-4900 5425);
WIRE 16 -1 (-6550 5425)(-5700 5425);
FORCEPROP 0 LAST CDS_PHYS_NET_NAME SMB_PEHPCPU1_GTL_SDA
J 0
(-6510 5473);
PAINT MONO (-6510 5473);
DISPLAY INVISIBLE (-6510 5473);
FORCEPROP 2 LAST SIG_NAME SMB_PEHPCPU1_GTL_SDA
J 0
(-6435 5435);
DISPLAY 0.510638 (-6435 5435);
PAINT WHITE (-6435 5435);
WIRE 16 -1 (-6550 5525)(-5700 5525);
FORCEPROP 0 LAST CDS_PHYS_NET_NAME SMB_PEHPCPU1_GTL_SCL
J 0
(-6510 5573);
PAINT MONO (-6510 5573);
DISPLAY INVISIBLE (-6510 5573);
FORCEPROP 2 LAST SIG_NAME SMB_PEHPCPU1_GTL_SCL
J 0
(-6435 5535);
DISPLAY 0.510638 (-6435 5535);
PAINT WHITE (-6435 5535);
WIRE 16 3135 (-6775 4150)(-6775 4025);
WIRE 16 3135 (-6775 4275)(-6775 4150);
WIRE 16 3135 (-6775 4025)(-6275 4025);
WIRE 16 3135 (-6275 4025)(-5550 4025);
WIRE 16 3135 (-5550 4025)(-5550 4150);
WIRE 16 3135 (-6775 4150)(-5550 4150);
WIRE 16 3135 (-5550 4150)(-5550 4275);
WIRE 16 3135 (-6275 4275)(-6275 4025);
WIRE 16 3135 (-6775 4275)(-6275 4275);
WIRE 16 3135 (-6275 4275)(-5550 4275);
WIRE 16 -1 (-4200 5275)(-4100 5275);
WIRE 16 -1 (-3150 5675)(-3250 5675);
WIRE 16 -1 (-3150 5675)(-3150 6200);
WIRE 16 -1 (-3000 6200)(-3000 6100);
WIRE 16 -1 (-3000 6200)(-3150 6200);
WIRE 16 -1 (-4350 6200)(-4350 6100);
WIRE 16 -1 (-4200 6200)(-4350 6200);
WIRE 16 -1 (-4200 5675)(-4200 6200);
WIRE 16 -1 (-4100 5675)(-4200 5675);
WIRE 16 -1 (-3250 7025)(-2100 7025);
FORCEPROP 0 LAST CDS_PHYS_NET_NAME SMB_PEHPCPU1_LVC3_SCL
J 0
(-3210 7073);
PAINT MONO (-3210 7073);
DISPLAY INVISIBLE (-3210 7073);
FORCEPROP 2 LAST SIG_NAME SMB_PEHPCPU0_LVC3_SDA_R0
J 0
(-3010 7035);
DISPLAY 0.510638 (-3010 7035);
PAINT WHITE (-3010 7035);
WIRE 16 -1 (-325 7025)(-550 7025);
WIRE 16 -1 (-550 7475)(-550 7025);
WIRE 16 -1 (-1900 7025)(-550 7025);
FORCEPROP 0 LAST CDS_PHYS_NET_NAME SMB_PEHPCPU0_LVC3_SDA
J 0
(-1860 7073);
PAINT MONO (-1860 7073);
DISPLAY INVISIBLE (-1860 7073);
FORCEPROP 2 LAST SIG_NAME SMB_PEHPCPU0_LVC3_SDA
J 0
(-1385 7035);
DISPLAY 0.510638 (-1385 7035);
PAINT WHITE (-1385 7035);
WIRE 16 -1 (-3250 7125)(-2100 7125);
FORCEPROP 0 LAST CDS_PHYS_NET_NAME SMB_PEHPCPU1_LVC3_SCL
J 0
(-3210 7173);
PAINT MONO (-3210 7173);
DISPLAY INVISIBLE (-3210 7173);
FORCEPROP 2 LAST SIG_NAME SMB_PEHPCPU0_LVC3_SCL_R0
J 0
(-3010 7135);
DISPLAY 0.510638 (-3010 7135);
PAINT WHITE (-3010 7135);
WIRE 16 -1 (-325 7125)(-750 7125);
WIRE 16 -1 (-750 7475)(-750 7125);
WIRE 16 -1 (-1900 7125)(-750 7125);
FORCEPROP 0 LAST CDS_PHYS_NET_NAME SMB_PEHPCPU0_LVC3_SCL
J 0
(-1860 7173);
PAINT MONO (-1860 7173);
DISPLAY INVISIBLE (-1860 7173);
FORCEPROP 2 LAST SIG_NAME SMB_PEHPCPU0_LVC3_SCL
J 0
(-1385 7135);
DISPLAY 0.510638 (-1385 7135);
PAINT WHITE (-1385 7135);
WIRE 16 -1 (-3250 5425)(-2100 5425);
FORCEPROP 0 LAST CDS_PHYS_NET_NAME SMB_PEHPCPU1_LVC3_SCL
J 0
(-3210 5473);
PAINT MONO (-3210 5473);
DISPLAY INVISIBLE (-3210 5473);
FORCEPROP 2 LAST SIG_NAME SMB_PEHPCPU1_LVC3_SDA_R0
J 0
(-3010 5435);
DISPLAY 0.510638 (-3010 5435);
PAINT WHITE (-3010 5435);
WIRE 16 -1 (-550 5875)(-550 5425);
WIRE 16 -1 (-325 5425)(-550 5425);
WIRE 16 -1 (-1900 5425)(-550 5425);
FORCEPROP 0 LAST CDS_PHYS_NET_NAME SMB_PEHPCPU1_LVC3_SDA
J 0
(-1860 5473);
PAINT MONO (-1860 5473);
DISPLAY INVISIBLE (-1860 5473);
FORCEPROP 2 LAST SIG_NAME SMB_PEHPCPU1_LVC3_SDA
J 0
(-1385 5435);
DISPLAY 0.510638 (-1385 5435);
PAINT WHITE (-1385 5435);
WIRE 16 -1 (-3250 5525)(-2100 5525);
FORCEPROP 0 LAST CDS_PHYS_NET_NAME SMB_PEHPCPU1_LVC3_SCL
J 0
(-3210 5573);
PAINT MONO (-3210 5573);
DISPLAY INVISIBLE (-3210 5573);
FORCEPROP 2 LAST SIG_NAME SMB_PEHPCPU1_LVC3_SCL_R0
J 0
(-3010 5535);
DISPLAY 0.510638 (-3010 5535);
PAINT WHITE (-3010 5535);
WIRE 16 -1 (-750 5875)(-750 5525);
WIRE 16 -1 (-750 5525)(-325 5525);
WIRE 16 -1 (-1900 5525)(-750 5525);
FORCEPROP 0 LAST CDS_PHYS_NET_NAME SMB_PEHPCPU1_LVC3_SCL
J 0
(-1860 5573);
PAINT MONO (-1860 5573);
DISPLAY INVISIBLE (-1860 5573);
FORCEPROP 2 LAST SIG_NAME SMB_PEHPCPU1_LVC3_SCL
J 0
(-1385 5535);
DISPLAY 0.510638 (-1385 5535);
PAINT WHITE (-1385 5535);
WIRE 16 -1 (-5125 7725)(-5125 7525);
WIRE 16 -1 (-4925 7725)(-5125 7725);
WIRE 16 -1 (-4925 7525)(-4925 7725);
WIRE 16 -1 (-750 7800)(-750 7675);
WIRE 16 -1 (-550 7675)(-550 7800);
WIRE 16 -1 (-550 7800)(-750 7800);
WIRE 16 -1 (-750 6200)(-750 6075);
WIRE 16 -1 (-550 6075)(-550 6200);
WIRE 16 -1 (-550 6200)(-750 6200);
WIRE 16 -1 (-6300 2450)(-5250 2450);
FORCEPROP 0 LAST CDS_PHYS_NET_NAME FM_SMB_PEHPCPU1_PCIE_ALERT_N
J 0
(-6275 2492);
PAINT MONO (-6275 2492);
DISPLAY INVISIBLE (-6275 2492);
FORCEPROP 0 LAST SIG_NAME FM_SMB_PEHPCPU1_PCIE_ALERT_N
J 0
(-6175 2460);
DISPLAY 0.553191 (-6175 2460);
PAINT WHITE (-6175 2460);
WIRE 16 -1 (-3250 6875)(-1975 6875);
FORCEPROP 0 LAST CDS_PHYS_NET_NAME TP_SMB_PEHPCPU0_EN
J 0
(-3210 6923);
PAINT MONO (-3210 6923);
DISPLAY INVISIBLE (-3210 6923);
FORCEPROP 2 LAST SIG_NAME TP_SMB_PEHPCPU0_EN
J 0
(-2985 6885);
DISPLAY 0.510638 (-2985 6885);
PAINT WHITE (-2985 6885);
WIRE 16 -1 (-3250 5275)(-1975 5275);
FORCEPROP 0 LAST CDS_PHYS_NET_NAME TP_SMB_PEHPCPU1_EN
J 0
(-3210 5323);
PAINT MONO (-3210 5323);
DISPLAY INVISIBLE (-3210 5323);
FORCEPROP 2 LAST SIG_NAME TP_SMB_PEHPCPU1_EN
J 0
(-2985 5285);
DISPLAY 0.510638 (-2985 5285);
PAINT WHITE (-2985 5285);
WIRE 16 -1 (-3000 7800)(-3000 7700);
WIRE 16 -1 (-3000 7800)(-3150 7800);
WIRE 16 -1 (-3150 7275)(-3150 7800);
WIRE 16 -1 (-3150 7275)(-3250 7275);
WIRE 16 -1 (-4350 7800)(-4350 7700);
WIRE 16 -1 (-4200 7800)(-4350 7800);
WIRE 16 -1 (-4200 7275)(-4200 7800);
WIRE 16 -1 (-4100 7275)(-4200 7275);
WIRE 16 -1 (-4200 6875)(-4100 6875);
WIRE 16 -1 (-6525 3150)(-5200 3150);
FORCEPROP 0 LAST CDS_PHYS_NET_NAME FM_SMB_PEHPCPU1_PCIE_ALERT_N
J 0
(-6500 3192);
PAINT MONO (-6500 3192);
DISPLAY INVISIBLE (-6500 3192);
FORCEPROP 0 LAST SIG_NAME FM_SMB_PEHPCPU1_PCIE_ALERT_N
J 0
(-6275 3160);
DISPLAY 0.680851 (-6275 3160);
PAINT WHITE (-6275 3160);
WIRE 16 -1 (-6525 3250)(-5200 3250);
FORCEPROP 0 LAST CDS_PHYS_NET_NAME FM_SMB_PEHPCPU0_PCIE_ALERT_N
J 0
(-6500 3292);
PAINT MONO (-6500 3292);
DISPLAY INVISIBLE (-6500 3292);
FORCEPROP 0 LAST SIG_NAME FM_SMB_PEHPCPU0_PCIE_ALERT_N
J 0
(-6275 3260);
DISPLAY 0.680851 (-6275 3260);
PAINT WHITE (-6275 3260);
DOT 1 (-5550 4150);
DOT 1 (-5125 5525);
DOT 1 (-750 7800);
DOT 1 (-550 7025);
DOT 1 (-750 7125);
DOT 1 (-750 6200);
DOT 1 (-750 5525);
DOT 1 (-550 5425);
DOT 1 (-6775 4150);
DOT 1 (-6275 4025);
DOT 1 (-6275 4275);
DOT 1 (-3975 3750);
DOT 1 (-4900 5425);
DOT 1 (-4350 6200);
DOT 1 (-2500 2775);
DOT 1 (-2500 4075);
DOT 1 (-3000 6200);
DOT 1 (-5125 7125);
DOT 1 (-5125 7725);
DOT 1 (-4925 7025);
DOT 1 (-4350 7800);
DOT 1 (-3000 7800);
DOT 1 (-1350 2775);
DOT 1 (-1350 4075);
DOT 1 (-5125 6125);
DOT 1 (-3975 2450);
FORCENOTE
20211129 R961,R962 CHANGE TO 10 OHM
(-6325 5175) 0;
DISPLAY LEFT (-6325 5175);
DISPLAY 1.063830 (-6325 5175);
PAINT WHITE (-6325 5175);
FORCENOTE
1-2          CPU0 PCIE ALERT
(-6725 4200) 0;
DISPLAY LEFT (-6725 4200);
DISPLAY 0.808511 (-6725 4200);
PAINT YELLOW (-6725 4200);
FORCENOTE
2-3          CPU1 PCIE ALERT
(-6725 4075) 0;
DISPLAY LEFT (-6725 4075);
DISPLAY 0.808511 (-6725 4075);
PAINT YELLOW (-6725 4075);
FORCENOTE
20211129 R960,R909 CHANGE TO 10 OHM
(-6275 6825) 0;
DISPLAY LEFT (-6275 6825);
DISPLAY 1.063830 (-6275 6825);
PAINT WHITE (-6275 6825);
FORCENOTE
20211215 R961,R962 CHANGE TO 33 OHM
(-6325 5100) 0;
DISPLAY LEFT (-6325 5100);
DISPLAY 1.063830 (-6325 5100);
PAINT WHITE (-6325 5100);
FORCENOTE
20211215 R960,R909 CHANGE TO 33 OHM
(-6275 6725) 0;
DISPLAY LEFT (-6275 6725);
DISPLAY 1.063830 (-6275 6725);
PAINT WHITE (-6275 6725);
QUIT
